G04 ================== begin FILE IDENTIFICATION RECORD ==================*
G04 Layout Name:  D:/<user>/Wistron_project/16315-1/gbr/16315-1.brd*
G04 Film Name:    L11GND*
G04 File Format:  Gerber RS274X*
G04 File Origin:  Cadence Allegro 16.5-S056*
G04 Origin Date:  Fri Jun 09 15:32:10 2017*
G04 *
G04 Layer:  VIA CLASS/L11GND*
G04 Layer:  PIN/L11GND*
G04 Layer:  ETCH/L11GND*
G04 Layer:  DRAWING FORMAT/LAYER_PCB_STORY*
G04 Layer:  DRAWING FORMAT/LAYER_L11GND*
G04 *
G04 Offset:    (0.00 0.00)*
G04 Mirror:    No*
G04 Mode:      Negative*
G04 Rotation:  0*
G04 FullContactRelief:  No*
G04 UndefLineWidth:     6.00*
G04 ================== end FILE IDENTIFICATION RECORD ====================*
%FSLAX35Y35*MOIN*%
%IR0*IPPOS*OFA0.00000B0.00000*MIA0B0*SFA1.00000B1.00000*%
%ADD24C,.03*%
%ADD43C,.04*%
%ADD14C,.032*%
%ADD41C,.052*%
%ADD32C,.043*%
%ADD22C,.036*%
%ADD20C,.081*%
%ADD19C,.065*%
%ADD37C,.057*%
%ADD42C,.058*%
%AMMACRO31*
4,1,15,.00398,.00044,
.003999,.000208,
.004004,-.000025,
.003996,-.000258,
.00398,-.00044,
.00483,-.00129,
.004897,-.001007,
.004947,-.000721,
.004981,-.000432,
.004997,-.000141,
.004997,.000149,
.00498,.00044,
.004946,.000729,
.004895,.001015,
.00483,.00129,
.00398,.00044,
90.*
4,1,15,.00044,-.00398,
.000208,-.003999,
-.000025,-.004004,
-.000258,-.003996,
-.00044,-.00398,
-.00129,-.00483,
-.001007,-.004897,
-.000721,-.004947,
-.000432,-.004981,
-.000141,-.004997,
.000149,-.004997,
.00044,-.00498,
.000729,-.004946,
.001015,-.004895,
.00129,-.00483,
.00044,-.00398,
90.*
4,1,15,-.00398,-.00044,
-.003999,-.000208,
-.004004,.000025,
-.003996,.000258,
-.00398,.00044,
-.00483,.00129,
-.004897,.001007,
-.004947,.000721,
-.004981,.000432,
-.004997,.000141,
-.004997,-.000149,
-.00498,-.00044,
-.004946,-.000729,
-.004895,-.001015,
-.00483,-.00129,
-.00398,-.00044,
90.*
4,1,15,-.00044,.00398,
-.000208,.003999,
.000025,.004004,
.000258,.003996,
.00044,.00398,
.00129,.00483,
.001007,.004897,
.000721,.004947,
.000432,.004981,
.000141,.004997,
-.000149,.004997,
-.00044,.00498,
-.000729,.004946,
-.001015,.004895,
-.00129,.00483,
-.00044,.00398,
90.*
%
%ADD31MACRO31*%
%AMMACRO28*
4,1,15,-.00398,.00044,
-.003999,.000208,
-.004004,-.000025,
-.003996,-.000258,
-.00398,-.00044,
-.00483,-.00129,
-.004897,-.001007,
-.004947,-.000721,
-.004981,-.000432,
-.004997,-.000141,
-.004997,.000149,
-.00498,.00044,
-.004946,.000729,
-.004895,.001015,
-.00483,.00129,
-.00398,.00044,
90.*
4,1,15,-.00044,-.00398,
-.000208,-.003999,
.000025,-.004004,
.000258,-.003996,
.00044,-.00398,
.00129,-.00483,
.001007,-.004897,
.000721,-.004947,
.000432,-.004981,
.000141,-.004997,
-.000149,-.004997,
-.00044,-.00498,
-.000729,-.004946,
-.001015,-.004895,
-.00129,-.00483,
-.00044,-.00398,
90.*
4,1,15,.00398,-.00044,
.003999,-.000208,
.004004,.000025,
.003996,.000258,
.00398,.00044,
.00483,.00129,
.004897,.001007,
.004947,.000721,
.004981,.000432,
.004997,.000141,
.004997,-.000149,
.00498,-.00044,
.004946,-.000729,
.004895,-.001015,
.00483,-.00129,
.00398,-.00044,
90.*
4,1,15,.00044,.00398,
.000208,.003999,
-.000025,.004004,
-.000258,.003996,
-.00044,.00398,
-.00129,.00483,
-.001007,.004897,
-.000721,.004947,
-.000432,.004981,
-.000141,.004997,
.000149,.004997,
.00044,.00498,
.000729,.004946,
.001015,.004895,
.00129,.00483,
.00044,.00398,
90.*
%
%ADD28MACRO28*%
%AMMACRO11*
4,1,15,.00398,.00044,
.003999,.000208,
.004004,-.000025,
.003996,-.000258,
.00398,-.00044,
.00483,-.00129,
.004897,-.001007,
.004947,-.000721,
.004981,-.000432,
.004997,-.000141,
.004997,.000149,
.00498,.00044,
.004946,.000729,
.004895,.001015,
.00483,.00129,
.00398,.00044,
0.0*
4,1,15,.00044,-.00398,
.000208,-.003999,
-.000025,-.004004,
-.000258,-.003996,
-.00044,-.00398,
-.00129,-.00483,
-.001007,-.004897,
-.000721,-.004947,
-.000432,-.004981,
-.000141,-.004997,
.000149,-.004997,
.00044,-.00498,
.000729,-.004946,
.001015,-.004895,
.00129,-.00483,
.00044,-.00398,
0.0*
4,1,15,-.00398,-.00044,
-.003999,-.000208,
-.004004,.000025,
-.003996,.000258,
-.00398,.00044,
-.00483,.00129,
-.004897,.001007,
-.004947,.000721,
-.004981,.000432,
-.004997,.000141,
-.004997,-.000149,
-.00498,-.00044,
-.004946,-.000729,
-.004895,-.001015,
-.00483,-.00129,
-.00398,-.00044,
0.0*
4,1,15,-.00044,.00398,
-.000208,.003999,
.000025,.004004,
.000258,.003996,
.00044,.00398,
.00129,.00483,
.001007,.004897,
.000721,.004947,
.000432,.004981,
.000141,.004997,
-.000149,.004997,
-.00044,.00498,
-.000729,.004946,
-.001015,.004895,
-.00129,.00483,
-.00044,.00398,
0.0*
%
%ADD11MACRO11*%
%AMMACRO36*
4,1,47,.19499,.0719,
.215281,.036007,
.229031,-.002865,
.235822,-.043533,
.235448,-.084763,
.22792,-.125302,
.213467,-.163917,
.192528,-.199436,
.16574,-.23078,
.133915,-.256995,
.098022,-.277286,
.059151,-.291036,
.018482,-.297827,
-.022748,-.297453,
-.063286,-.289925,
-.101902,-.275472,
-.137421,-.254533,
-.168764,-.227745,
-.19498,-.19592,
-.215271,-.160027,
-.229021,-.121156,
-.235812,-.080487,
-.235438,-.039257,
-.22791,.001281,
-.213457,.039897,
-.19498,.0719,
-.17079,.109417,
-.148822,.148276,
-.129151,.188348,
-.11538,.22052,
-.105587,.239854,
-.092586,.257193,
-.076771,.272012,
-.058623,.283859,
-.038693,.292375,
-.017588,.297301,
.004052,.298487,
.025569,.295897,
.04631,.28961,
.065644,.279817,
.082983,.266816,
.097802,.251001,
.109649,.232853,
.1154,.22052,
.133222,.179593,
.153393,.139771,
.175846,.101189,
.19499,.0719,
0.0*
%
%ADD36MACRO36*%
%AMMACRO23*
4,1,15,-.00398,.00044,
-.003999,.000208,
-.004004,-.000025,
-.003996,-.000258,
-.00398,-.00044,
-.00483,-.00129,
-.004897,-.001007,
-.004947,-.000721,
-.004981,-.000432,
-.004997,-.000141,
-.004997,.000149,
-.00498,.00044,
-.004946,.000729,
-.004895,.001015,
-.00483,.00129,
-.00398,.00044,
0.0*
4,1,15,-.00044,-.00398,
-.000208,-.003999,
.000025,-.004004,
.000258,-.003996,
.00044,-.00398,
.00129,-.00483,
.001007,-.004897,
.000721,-.004947,
.000432,-.004981,
.000141,-.004997,
-.000149,-.004997,
-.00044,-.00498,
-.000729,-.004946,
-.001015,-.004895,
-.00129,-.00483,
-.00044,-.00398,
0.0*
4,1,15,.00398,-.00044,
.003999,-.000208,
.004004,.000025,
.003996,.000258,
.00398,.00044,
.00483,.00129,
.004897,.001007,
.004947,.000721,
.004981,.000432,
.004997,.000141,
.004997,-.000149,
.00498,-.00044,
.004946,-.000729,
.004895,-.001015,
.00483,-.00129,
.00398,-.00044,
0.0*
4,1,15,.00044,.00398,
.000208,.003999,
-.000025,.004004,
-.000258,.003996,
-.00044,.00398,
-.00129,.00483,
-.001007,.004897,
-.000721,.004947,
-.000432,.004981,
-.000141,.004997,
.000149,.004997,
.00044,.00498,
.000729,.004946,
.001015,.004895,
.00129,.00483,
.00044,.00398,
0.0*
%
%ADD23MACRO23*%
%ADD38C,.121*%
%ADD33C,.122*%
%ADD15C,.114*%
%ADD18C,.115*%
%ADD12O,.206X.285*%
%ADD34C,.125*%
%ADD10C,.206*%
%ADD35C,.432*%
%ADD26C,.18*%
%ADD13C,.208*%
%ADD39O,.159X.237*%
%ADD27C,.139*%
%ADD17C,.265*%
%ADD40C,.159*%
%ADD44C,.178*%
%AMMACRO25*
4,1,15,.00398,.00044,
.003999,.000208,
.004004,-.000025,
.003996,-.000258,
.00398,-.00044,
.00483,-.00129,
.004897,-.001007,
.004947,-.000721,
.004981,-.000432,
.004997,-.000141,
.004997,.000149,
.00498,.00044,
.004946,.000729,
.004895,.001015,
.00483,.00129,
.00398,.00044,
270.*
4,1,15,.00044,-.00398,
.000208,-.003999,
-.000025,-.004004,
-.000258,-.003996,
-.00044,-.00398,
-.00129,-.00483,
-.001007,-.004897,
-.000721,-.004947,
-.000432,-.004981,
-.000141,-.004997,
.000149,-.004997,
.00044,-.00498,
.000729,-.004946,
.001015,-.004895,
.00129,-.00483,
.00044,-.00398,
270.*
4,1,15,-.00398,-.00044,
-.003999,-.000208,
-.004004,.000025,
-.003996,.000258,
-.00398,.00044,
-.00483,.00129,
-.004897,.001007,
-.004947,.000721,
-.004981,.000432,
-.004997,.000141,
-.004997,-.000149,
-.00498,-.00044,
-.004946,-.000729,
-.004895,-.001015,
-.00483,-.00129,
-.00398,-.00044,
270.*
4,1,15,-.00044,.00398,
-.000208,.003999,
.000025,.004004,
.000258,.003996,
.00044,.00398,
.00129,.00483,
.001007,.004897,
.000721,.004947,
.000432,.004981,
.000141,.004997,
-.000149,.004997,
-.00044,.00498,
-.000729,.004946,
-.001015,.004895,
-.00129,.00483,
-.00044,.00398,
270.*
%
%ADD25MACRO25*%
%AMMACRO16*
4,1,15,.00398,.00044,
.003999,.000208,
.004004,-.000025,
.003996,-.000258,
.00398,-.00044,
.00483,-.00129,
.004897,-.001007,
.004947,-.000721,
.004981,-.000432,
.004997,-.000141,
.004997,.000149,
.00498,.00044,
.004946,.000729,
.004895,.001015,
.00483,.00129,
.00398,.00044,
180.*
4,1,15,.00044,-.00398,
.000208,-.003999,
-.000025,-.004004,
-.000258,-.003996,
-.00044,-.00398,
-.00129,-.00483,
-.001007,-.004897,
-.000721,-.004947,
-.000432,-.004981,
-.000141,-.004997,
.000149,-.004997,
.00044,-.00498,
.000729,-.004946,
.001015,-.004895,
.00129,-.00483,
.00044,-.00398,
180.*
4,1,15,-.00398,-.00044,
-.003999,-.000208,
-.004004,.000025,
-.003996,.000258,
-.00398,.00044,
-.00483,.00129,
-.004897,.001007,
-.004947,.000721,
-.004981,.000432,
-.004997,.000141,
-.004997,-.000149,
-.00498,-.00044,
-.004946,-.000729,
-.004895,-.001015,
-.00483,-.00129,
-.00398,-.00044,
180.*
4,1,15,-.00044,.00398,
-.000208,.003999,
.000025,.004004,
.000258,.003996,
.00044,.00398,
.00129,.00483,
.001007,.004897,
.000721,.004947,
.000432,.004981,
.000141,.004997,
-.000149,.004997,
-.00044,.00498,
-.000729,.004946,
-.001015,.004895,
-.00129,.00483,
-.00044,.00398,
180.*
%
%ADD16MACRO16*%
%AMMACRO30*
4,1,15,-.00398,.00044,
-.003999,.000208,
-.004004,-.000025,
-.003996,-.000258,
-.00398,-.00044,
-.00483,-.00129,
-.004897,-.001007,
-.004947,-.000721,
-.004981,-.000432,
-.004997,-.000141,
-.004997,.000149,
-.00498,.00044,
-.004946,.000729,
-.004895,.001015,
-.00483,.00129,
-.00398,.00044,
270.*
4,1,15,-.00044,-.00398,
-.000208,-.003999,
.000025,-.004004,
.000258,-.003996,
.00044,-.00398,
.00129,-.00483,
.001007,-.004897,
.000721,-.004947,
.000432,-.004981,
.000141,-.004997,
-.000149,-.004997,
-.00044,-.00498,
-.000729,-.004946,
-.001015,-.004895,
-.00129,-.00483,
-.00044,-.00398,
270.*
4,1,15,.00398,-.00044,
.003999,-.000208,
.004004,.000025,
.003996,.000258,
.00398,.00044,
.00483,.00129,
.004897,.001007,
.004947,.000721,
.004981,.000432,
.004997,.000141,
.004997,-.000149,
.00498,-.00044,
.004946,-.000729,
.004895,-.001015,
.00483,-.00129,
.00398,-.00044,
270.*
4,1,15,.00044,.00398,
.000208,.003999,
-.000025,.004004,
-.000258,.003996,
-.00044,.00398,
-.00129,.00483,
-.001007,.004897,
-.000721,.004947,
-.000432,.004981,
-.000141,.004997,
.000149,.004997,
.00044,.00498,
.000729,.004946,
.001015,.004895,
.00129,.00483,
.00044,.00398,
270.*
%
%ADD30MACRO30*%
%AMMACRO29*
4,1,15,-.00398,.00044,
-.003999,.000208,
-.004004,-.000025,
-.003996,-.000258,
-.00398,-.00044,
-.00483,-.00129,
-.004897,-.001007,
-.004947,-.000721,
-.004981,-.000432,
-.004997,-.000141,
-.004997,.000149,
-.00498,.00044,
-.004946,.000729,
-.004895,.001015,
-.00483,.00129,
-.00398,.00044,
180.*
4,1,15,-.00044,-.00398,
-.000208,-.003999,
.000025,-.004004,
.000258,-.003996,
.00044,-.00398,
.00129,-.00483,
.001007,-.004897,
.000721,-.004947,
.000432,-.004981,
.000141,-.004997,
-.000149,-.004997,
-.00044,-.00498,
-.000729,-.004946,
-.001015,-.004895,
-.00129,-.00483,
-.00044,-.00398,
180.*
4,1,15,.00398,-.00044,
.003999,-.000208,
.004004,.000025,
.003996,.000258,
.00398,.00044,
.00483,.00129,
.004897,.001007,
.004947,.000721,
.004981,.000432,
.004997,.000141,
.004997,-.000149,
.00498,-.00044,
.004946,-.000729,
.004895,-.001015,
.00483,-.00129,
.00398,-.00044,
180.*
4,1,15,.00044,.00398,
.000208,.003999,
-.000025,.004004,
-.000258,.003996,
-.00044,.00398,
-.00129,.00483,
-.001007,.004897,
-.000721,.004947,
-.000432,.004981,
-.000141,.004997,
.000149,.004997,
.00044,.00498,
.000729,.004946,
.001015,.004895,
.00129,.00483,
.00044,.00398,
180.*
%
%ADD29MACRO29*%
%ADD45C,.02*%
%ADD46C,.006*%
%ADD56C,.06104*%
%ADD57C,.07704*%
%ADD58C,.11004*%
%ADD55C,.11104*%
%ADD62C,.11704*%
%ADD59C,.13504*%
%ADD61C,.11804*%
%ADD54C,.37504*%
%ADD64C,.29531*%
%ADD53C,.29532*%
%ADD63C,.29533*%
%ADD60C,.23629*%
%ADD47O,.55202X.78802*%
%ADD50O,.09834X.04322*%
%ADD48O,.55204X.78804*%
%ADD52O,.09854X.04342*%
%ADD49O,.09836X.04324*%
%ADD51O,.09856X.04344*%
G75*
%LPD*%
G75*
G36*
G01X-6000Y-158756D02*
X1940843D01*
Y1664268D01*
X-6000D01*
Y-158756D01*
G37*
%LPC*%
G75*
G36*
G01X1216535Y1655264D02*
G02X1217468Y1654331I0J-933D01*
G01Y1476378D01*
G02X1216535Y1475445I-933J0D01*
G01X1168110D01*
G03X1161169Y1468504I0J-6941D01*
G01Y1378740D01*
G03X1168110Y1371799I6941J0D01*
G01X1930906D01*
G02X1931839Y1370866I0J-933D01*
G01Y3937D01*
G02X1930906Y3004I-933J0D01*
G01X1562992D01*
G02X1562059Y3937I0J933D01*
G01Y55118D01*
G03X1555118Y62059I-6941J0D01*
G01X1374016D01*
G03X1367075Y55118I0J-6941D01*
G01Y3937D01*
G02X1366142Y3004I-933J0D01*
G01X1185039D01*
G03X1178098Y-3937I0J-6941D01*
G01Y-148819D01*
G02X1177165Y-149752I-933J0D01*
G01X870079D01*
G02X869146Y-148819I0J933D01*
G01Y-11811D01*
G03X862205Y-4870I-6941J0D01*
G01X791339D01*
G02X790406Y-3937I0J933D01*
G03X783465Y3004I-6941J0D01*
G01X594488D01*
G02X593555Y3937I0J933D01*
G01Y55118D01*
G03X586614Y62059I-6941J0D01*
G01X405512D01*
G03X398571Y55118I0J-6941D01*
G01Y3937D01*
G02X397638Y3004I-933J0D01*
G01X3937D01*
G02X3004Y3937I0J933D01*
G01Y12071D01*
G02X3714Y12323I400J0D01*
G03X29922Y21653I11443J9331D01*
G01Y21654D01*
G03X3714Y30984I-14765J0D01*
G02X3004Y31236I-310J253D01*
G01Y464768D01*
G02X3713Y465022I400J0D01*
G03X12310Y459884I11444J9387D01*
G03X18004I2847J10575D01*
G03Y488934I-2847J14525D01*
G03X12310I-2847J-10575D01*
G03X3713Y483796I2847J-14525D01*
G02X3004Y484050I-309J254D01*
G01Y1370866D01*
G02X3937Y1371799I933J0D01*
G01X746850D01*
G03X753791Y1378740I0J6941D01*
G01Y1464567D01*
G02X754724Y1465500I933J0D01*
G01X783465D01*
G03X790406Y1472441I0J6941D01*
G01Y1654331D01*
G02X791339Y1655264I933J0D01*
G01X1216535D01*
G37*
%LPD*%
G75*
G36*
G01X1124313Y534842D02*
X1124318Y534833D01*
X1116440Y530894D01*
X1116437Y530899D01*
X1116339Y530857D01*
G02X1113786Y535977I-1183J2607D01*
G01X1113872Y536027D01*
X1113870Y536032D01*
X1121747Y539971D01*
X1121753Y539965D01*
X1121814Y539992D01*
G02X1124313Y534842I1217J-2591D01*
G37*
G36*
G01X956203D02*
X956208Y534833D01*
X948330Y530894D01*
X948327Y530899D01*
X948229Y530857D01*
G02X945676Y535977I-1183J2607D01*
G01X945762Y536027D01*
X945760Y536032D01*
X953637Y539971D01*
X953643Y539965D01*
X953704Y539992D01*
G02X956203Y534842I1217J-2591D01*
G37*
G36*
G01X1897508Y459879D02*
G02X1891860I-2824J10580D01*
G02Y488939I2824J14530D01*
G02X1897508I2824J-10580D01*
G02Y459879I-2824J-14530D01*
G37*
G36*
G01X956203Y424606D02*
X956208Y424597D01*
X948330Y420658D01*
X948327Y420663D01*
X948229Y420621D01*
G02X945676Y425741I-1183J2607D01*
G01X945762Y425791D01*
X945760Y425796D01*
X953637Y429735D01*
X953643Y429729D01*
X953704Y429756D01*
G02X956203Y424606I1217J-2591D01*
G37*
G36*
G01X907745Y-40121D02*
G02X902097I-2824J10580D01*
G02Y-11061I2824J14530D01*
G02X907745I2824J-10580D01*
G02Y-40121I-2824J-14530D01*
G37*
G36*
G01X1535036Y77756D02*
Y72244D01*
G02X1530712Y72245I-2162J1D01*
G01Y77756D01*
G02X1535036I2162J0D01*
G37*
G36*
G01Y91930D02*
Y86417D01*
G02X1530712Y86418I-2162J1D01*
G01Y91930D01*
G02X1535036I2162J0D01*
G37*
G36*
G01X1527948Y87993D02*
Y82480D01*
G02X1523626Y82481I-2161J1D01*
G01Y87993D01*
G02X1527948I2161J0D01*
G37*
G36*
G01X1535036Y120276D02*
Y114763D01*
G02X1530712Y114764I-2162J1D01*
G01Y120276D01*
G02X1535036I2162J0D01*
G37*
G36*
G01X1527948Y73819D02*
Y68306D01*
G02X1523626Y68307I-2161J1D01*
G01Y73819D01*
G02X1527948I2161J0D01*
G37*
G36*
G01X1520862Y77756D02*
Y72244D01*
G02X1516540Y72245I-2161J1D01*
G01Y77756D01*
G02X1520862I2161J0D01*
G37*
G36*
G01X1506690D02*
Y72244D01*
G02X1502366Y72245I-2162J1D01*
G01Y77756D01*
G02X1506690I2162J0D01*
G37*
G36*
G01X1492516D02*
Y72244D01*
G02X1488192Y72245I-2162J1D01*
G01Y77756D01*
G02X1492516I2162J0D01*
G37*
G36*
G01X1520862Y91930D02*
Y86417D01*
G02X1516540Y86418I-2161J1D01*
G01Y91930D01*
G02X1520862I2161J0D01*
G37*
G36*
G01X1513776Y87993D02*
Y82480D01*
G02X1509452Y82481I-2162J1D01*
G01Y87993D01*
G02X1513776I2162J0D01*
G37*
G36*
G01X1506690Y91930D02*
Y86417D01*
G02X1502366Y86418I-2162J1D01*
G01Y91930D01*
G02X1506690I2162J0D01*
G37*
G36*
G01X1499602Y87993D02*
Y82480D01*
G02X1495280Y82481I-2161J1D01*
G01Y87993D01*
G02X1499602I2161J0D01*
G37*
G36*
G01X1492516Y91930D02*
Y86417D01*
G02X1488192Y86418I-2162J1D01*
G01Y91930D01*
G02X1492516I2162J0D01*
G37*
G36*
G01X1485430Y87993D02*
Y82480D01*
G02X1481106Y82481I-2162J1D01*
G01Y87993D01*
G02X1485430I2162J0D01*
G37*
G36*
G01X1506700Y120276D02*
Y114763D01*
G02X1502356Y114764I-2172J1D01*
G01Y120276D01*
G02X1506700I2172J0D01*
G37*
G36*
G01X1513776Y73819D02*
Y68306D01*
G02X1509452Y68307I-2162J1D01*
G01Y73819D01*
G02X1513776I2162J0D01*
G37*
G36*
G01X1499602D02*
Y68306D01*
G02X1495280Y68307I-2161J1D01*
G01Y73819D01*
G02X1499602I2161J0D01*
G37*
G36*
G01X1485430D02*
Y68306D01*
G02X1481106Y68307I-2162J1D01*
G01Y73819D01*
G02X1485430I2162J0D01*
G37*
G36*
G01X1449996Y77756D02*
Y72244D01*
G02X1445674Y72245I-2161J1D01*
G01Y77756D01*
G02X1449996I2161J0D01*
G37*
G36*
G01X1435822D02*
Y72244D01*
G02X1431500Y72245I-2161J1D01*
G01Y77756D01*
G02X1435822I2161J0D01*
G37*
G36*
G01X1449996Y91930D02*
Y86417D01*
G02X1445674Y86418I-2161J1D01*
G01Y91930D01*
G02X1449996I2161J0D01*
G37*
G36*
G01X1442910Y87993D02*
Y82480D01*
G02X1438586Y82481I-2162J1D01*
G01Y87993D01*
G02X1442910I2162J0D01*
G37*
G36*
G01X1435822Y91930D02*
Y86417D01*
G02X1431500Y86418I-2161J1D01*
G01Y91930D01*
G02X1435822I2161J0D01*
G37*
G36*
G01X1445664Y114764D02*
Y120277D01*
G02X1450006Y120276I2171J-1D01*
G01Y114764D01*
G02X1445664I-2171J0D01*
G37*
G36*
G01X1442910Y73819D02*
Y68306D01*
G02X1438586Y68307I-2162J1D01*
G01Y73819D01*
G02X1442910I2162J0D01*
G37*
G36*
G01X1404234Y190242D02*
Y185741D01*
G02X1401192Y185742I-1521J1D01*
G01Y190242D01*
G02X1404234I1521J0D01*
G37*
G36*
G01X1385463Y166302D02*
X1380962D01*
G02X1380963Y169344I1J1521D01*
G01X1385463D01*
G02Y166302I0J-1521D01*
G37*
G36*
G01X1421650Y77756D02*
Y72244D01*
G02X1417326Y72245I-2162J1D01*
G01Y77756D01*
G02X1421650I2162J0D01*
G37*
G36*
G01X1407476D02*
Y72244D01*
G02X1403154Y72245I-2161J1D01*
G01Y77756D01*
G02X1407476I2161J0D01*
G37*
G36*
G01X1428736Y87993D02*
Y82480D01*
G02X1424414Y82481I-2161J1D01*
G01Y87993D01*
G02X1428736I2161J0D01*
G37*
G36*
G01X1421650Y91930D02*
Y86417D01*
G02X1417326Y86418I-2162J1D01*
G01Y91930D01*
G02X1421650I2162J0D01*
G37*
G36*
G01X1414564Y87993D02*
Y82480D01*
G02X1410240Y82481I-2162J1D01*
G01Y87993D01*
G02X1414564I2162J0D01*
G37*
G36*
G01X1407476Y91930D02*
Y86417D01*
G02X1403154Y86418I-2161J1D01*
G01Y91930D01*
G02X1407476I2161J0D01*
G37*
G36*
G01X1400390Y87993D02*
Y82480D01*
G02X1396066Y82481I-2162J1D01*
G01Y87993D01*
G02X1400390I2162J0D01*
G37*
G36*
G01X1428736Y116339D02*
Y110826D01*
G02X1424414Y110827I-2161J1D01*
G01Y116339D01*
G02X1428736I2161J0D01*
G37*
G36*
G01Y73819D02*
Y68306D01*
G02X1424414Y68307I-2161J1D01*
G01Y73819D01*
G02X1428736I2161J0D01*
G37*
G36*
G01X1414564D02*
Y68306D01*
G02X1410240Y68307I-2162J1D01*
G01Y73819D01*
G02X1414564I2162J0D01*
G37*
G36*
G01X1400390D02*
Y68306D01*
G02X1396066Y68307I-2162J1D01*
G01Y73819D01*
G02X1400390I2162J0D01*
G37*
G36*
G01X1261462Y1080754D02*
Y1076253D01*
G02X1258138Y1076254I-1662J1D01*
G01Y1080754D01*
G02X1261462I1662J0D01*
G37*
G36*
G01X1113922Y709162D02*
X1121763Y713082D01*
X1121764Y713083D01*
G02X1124266Y708159I1267J-2454D01*
G01X1116392Y704222D01*
G02X1113922Y709162I-1235J2470D01*
G37*
G36*
G01X1104199Y696183D02*
X1104034Y696253D01*
X1104032Y696249D01*
X1096156Y700187D01*
Y700195D01*
X1096053Y700252D01*
G02X1098557Y705390I1388J2503D01*
G01X1098722Y705320D01*
X1098724Y705324D01*
X1106601Y701386D01*
X1106599Y701382D01*
X1106767Y701283D01*
G02X1104199Y696183I-1453J-2465D01*
G37*
G36*
G01X1113922Y693414D02*
X1121763Y697334D01*
X1121764Y697335D01*
G02X1124266Y692411I1267J-2454D01*
G01X1116392Y688474D01*
G02X1113922Y693414I-1235J2470D01*
G37*
G36*
G01Y677666D02*
X1121763Y681586D01*
X1121764Y681587D01*
G02X1124266Y676663I1267J-2454D01*
G01X1116392Y672726D01*
G02X1113922Y677666I-1235J2470D01*
G37*
G36*
G01Y661918D02*
X1121763Y665838D01*
X1121764Y665839D01*
G02X1124266Y660915I1267J-2454D01*
G01X1116392Y656978D01*
G02X1113922Y661918I-1235J2470D01*
G37*
G36*
G01X1104199Y680435D02*
X1104034Y680505D01*
X1104032Y680501D01*
X1096156Y684439D01*
Y684447D01*
X1096053Y684504D01*
G02X1098557Y689642I1388J2503D01*
G01X1098722Y689572D01*
X1098724Y689576D01*
X1106601Y685638D01*
X1106599Y685634D01*
X1106767Y685535D01*
G02X1104199Y680435I-1453J-2465D01*
G37*
G36*
G01Y664687D02*
X1104034Y664757D01*
X1104032Y664753D01*
X1096156Y668691D01*
Y668699D01*
X1096053Y668756D01*
G02X1098557Y673894I1388J2503D01*
G01X1098722Y673824D01*
X1098724Y673828D01*
X1106601Y669890D01*
X1106599Y669886D01*
X1106767Y669787D01*
G02X1104199Y664687I-1453J-2465D01*
G37*
G36*
G01Y648939D02*
X1104034Y649009D01*
X1104032Y649005D01*
X1096156Y652943D01*
Y652951D01*
X1096053Y653008D01*
G02X1098557Y658146I1388J2503D01*
G01X1098722Y658076D01*
X1098724Y658080D01*
X1106601Y654142D01*
X1106599Y654138D01*
X1106767Y654039D01*
G02X1104199Y648939I-1453J-2465D01*
G37*
G36*
G01X1113922Y646170D02*
X1121763Y650090D01*
X1121764Y650091D01*
G02X1124266Y645167I1267J-2454D01*
G01X1116392Y641230D01*
G02X1113922Y646170I-1235J2470D01*
G37*
G36*
G01X1124266Y629419D02*
X1116425Y625499D01*
X1116424Y625498D01*
G02X1113922Y630422I-1267J2454D01*
G01X1121796Y634359D01*
G02X1124266Y629419I1235J-2470D01*
G37*
G36*
G01X1113922Y614674D02*
X1121763Y618594D01*
X1121764Y618595D01*
G02X1124266Y613671I1267J-2454D01*
G01X1116392Y609734D01*
G02X1113922Y614674I-1235J2470D01*
G37*
G36*
G01X1104039Y601780D02*
X1096133Y605733D01*
X1096062Y605771D01*
G02X1098717Y610817I1379J2496D01*
G01X1106591Y606880D01*
G02X1104039Y601780I-1276J-2550D01*
G37*
G36*
G01Y617528D02*
X1096133Y621481D01*
X1096062Y621519D01*
G02X1098717Y626565I1379J2496D01*
G01X1106591Y622628D01*
G02X1104039Y617528I-1276J-2550D01*
G37*
G36*
G01Y633276D02*
X1096133Y637229D01*
X1096062Y637267D01*
G02X1098717Y642313I1379J2496D01*
G01X1106591Y638376D01*
G02X1104039Y633276I-1276J-2550D01*
G37*
G36*
G01X1113922Y598926D02*
X1121763Y602846D01*
X1121764Y602847D01*
G02X1124266Y597923I1267J-2454D01*
G01X1116392Y593986D01*
G02X1113922Y598926I-1235J2470D01*
G37*
G36*
G01X1104039Y586032D02*
X1096133Y589985D01*
X1096062Y590023D01*
G02X1098717Y595069I1379J2496D01*
G01X1106591Y591132D01*
G02X1104039Y586032I-1276J-2550D01*
G37*
G36*
G01Y507292D02*
X1096133Y511245D01*
X1096062Y511283D01*
G02X1098717Y516329I1379J2496D01*
G01X1106591Y512392D01*
G02X1104039Y507292I-1276J-2550D01*
G37*
G36*
G01X1104199Y538703D02*
X1104034Y538773D01*
X1104032Y538769D01*
X1096156Y542707D01*
Y542715D01*
X1096053Y542772D01*
G02X1098557Y547910I1388J2503D01*
G01X1098722Y547840D01*
X1098724Y547844D01*
X1106601Y543906D01*
X1106599Y543902D01*
X1106767Y543803D01*
G02X1104199Y538703I-1453J-2465D01*
G37*
G36*
G01X1113922Y504438D02*
X1121763Y508358D01*
X1121764Y508359D01*
G02X1124266Y503435I1267J-2454D01*
G01X1116392Y499498D01*
G02X1113922Y504438I-1235J2470D01*
G37*
G36*
G01Y488690D02*
X1121763Y492610D01*
X1121764Y492611D01*
G02X1124266Y487687I1267J-2454D01*
G01X1116392Y483750D01*
G02X1113922Y488690I-1235J2470D01*
G37*
G36*
G01Y472942D02*
X1121763Y476862D01*
X1121764Y476863D01*
G02X1124266Y471939I1267J-2454D01*
G01X1116392Y468002D01*
G02X1113922Y472942I-1235J2470D01*
G37*
G36*
G01X1104039Y460048D02*
X1096133Y464001D01*
X1096062Y464039D01*
G02X1098717Y469085I1379J2496D01*
G01X1106591Y465148D01*
G02X1104039Y460048I-1276J-2550D01*
G37*
G36*
G01Y475796D02*
X1096133Y479749D01*
X1096062Y479787D01*
G02X1098717Y484833I1379J2496D01*
G01X1106591Y480896D01*
G02X1104039Y475796I-1276J-2550D01*
G37*
G36*
G01Y491544D02*
X1096133Y495497D01*
X1096062Y495535D01*
G02X1098717Y500581I1379J2496D01*
G01X1106591Y496644D01*
G02X1104039Y491544I-1276J-2550D01*
G37*
G36*
G01X1098676Y453257D02*
X1106550Y449320D01*
G02X1104080Y444380I-1235J-2470D01*
G01X1096239Y448301D01*
X1096238D01*
G02X1098676Y453257I1203J2486D01*
G37*
G36*
G01X1113922Y457194D02*
X1121763Y461114D01*
X1121764Y461115D01*
G02X1124266Y456191I1267J-2454D01*
G01X1116392Y452254D01*
G02X1113922Y457194I-1235J2470D01*
G37*
G36*
G01X1113872Y425796D02*
X1121746Y429733D01*
G02X1124316Y424597I1285J-2568D01*
G01X1116442Y420660D01*
G02X1113872Y425796I-1285J2568D01*
G37*
G36*
G01X1113922Y330029D02*
X1121763Y333949D01*
X1121764Y333950D01*
G02X1124266Y329026I1267J-2454D01*
G01X1116392Y325089D01*
G02X1113922Y330029I-1235J2470D01*
G37*
G36*
G01X1104199Y317050D02*
X1104034Y317120D01*
X1104032Y317116D01*
X1096156Y321054D01*
Y321062D01*
X1096053Y321119D01*
G02X1098557Y326257I1388J2503D01*
G01X1098722Y326187D01*
X1098724Y326191D01*
X1106601Y322253D01*
X1106599Y322249D01*
X1106767Y322150D01*
G02X1104199Y317050I-1453J-2465D01*
G37*
G36*
G01X1113922Y314281D02*
X1121763Y318201D01*
X1121764Y318202D01*
G02X1124266Y313278I1267J-2454D01*
G01X1116392Y309341D01*
G02X1113922Y314281I-1235J2470D01*
G37*
G36*
G01Y282785D02*
X1121763Y286705D01*
X1121764Y286706D01*
G02X1124266Y281782I1267J-2454D01*
G01X1116392Y277845D01*
G02X1113922Y282785I-1235J2470D01*
G37*
G36*
G01Y267037D02*
X1121763Y270957D01*
X1121764Y270958D01*
G02X1124266Y266034I1267J-2454D01*
G01X1116392Y262097D01*
G02X1113922Y267037I-1235J2470D01*
G37*
G36*
G01X1104199Y269806D02*
X1104034Y269876D01*
X1104032Y269872D01*
X1096156Y273810D01*
Y273818D01*
X1096053Y273875D01*
G02X1098557Y279013I1388J2503D01*
G01X1098722Y278943D01*
X1098724Y278947D01*
X1106601Y275009D01*
X1106599Y275005D01*
X1106767Y274906D01*
G02X1104199Y269806I-1453J-2465D01*
G37*
G36*
G01Y301302D02*
X1104034Y301372D01*
X1104032Y301368D01*
X1096156Y305306D01*
Y305314D01*
X1096053Y305371D01*
G02X1098557Y310509I1388J2503D01*
G01X1098722Y310439D01*
X1098724Y310443D01*
X1106601Y306505D01*
X1106599Y306501D01*
X1106767Y306402D01*
G02X1104199Y301302I-1453J-2465D01*
G37*
G36*
G01Y285554D02*
X1104034Y285624D01*
X1104032Y285620D01*
X1096156Y289558D01*
Y289566D01*
X1096053Y289623D01*
G02X1098557Y294761I1388J2503D01*
G01X1098722Y294691D01*
X1098724Y294695D01*
X1106601Y290757D01*
X1106599Y290753D01*
X1106767Y290654D01*
G02X1104199Y285554I-1453J-2465D01*
G37*
G36*
G01X1113922Y298533D02*
X1121763Y302453D01*
X1121764Y302454D01*
G02X1124266Y297530I1267J-2454D01*
G01X1116392Y293593D01*
G02X1113922Y298533I-1235J2470D01*
G37*
G36*
G01Y219793D02*
X1121763Y223713D01*
X1121764Y223714D01*
G02X1124266Y218790I1267J-2454D01*
G01X1116392Y214853D01*
G02X1113922Y219793I-1235J2470D01*
G37*
G36*
G01Y235541D02*
X1121763Y239461D01*
X1121764Y239462D01*
G02X1124266Y234538I1267J-2454D01*
G01X1116392Y230601D01*
G02X1113922Y235541I-1235J2470D01*
G37*
G36*
G01X1104199Y222562D02*
X1104034Y222632D01*
X1104032Y222628D01*
X1096156Y226566D01*
Y226574D01*
X1096053Y226631D01*
G02X1098557Y231769I1388J2503D01*
G01X1098722Y231699D01*
X1098724Y231703D01*
X1106601Y227765D01*
X1106599Y227761D01*
X1106767Y227662D01*
G02X1104199Y222562I-1453J-2465D01*
G37*
G36*
G01X1113922Y251289D02*
X1121763Y255209D01*
X1121764Y255210D01*
G02X1124266Y250286I1267J-2454D01*
G01X1116392Y246349D01*
G02X1113922Y251289I-1235J2470D01*
G37*
G36*
G01X1104199Y254058D02*
X1104034Y254128D01*
X1104032Y254124D01*
X1096156Y258062D01*
Y258070D01*
X1096053Y258127D01*
G02X1098557Y263265I1388J2503D01*
G01X1098722Y263195D01*
X1098724Y263199D01*
X1106601Y259261D01*
X1106599Y259257D01*
X1106767Y259158D01*
G02X1104199Y254058I-1453J-2465D01*
G37*
G36*
G01Y238310D02*
X1104034Y238380D01*
X1104032Y238376D01*
X1096156Y242314D01*
Y242322D01*
X1096053Y242379D01*
G02X1098557Y247517I1388J2503D01*
G01X1098722Y247447D01*
X1098724Y247451D01*
X1106601Y243513D01*
X1106599Y243509D01*
X1106767Y243410D01*
G02X1104199Y238310I-1453J-2465D01*
G37*
G36*
G01X1113922Y172549D02*
X1121763Y176469D01*
X1121764Y176470D01*
G02X1124266Y171546I1267J-2454D01*
G01X1116392Y167609D01*
G02X1113922Y172549I-1235J2470D01*
G37*
G36*
G01Y188297D02*
X1121763Y192217D01*
X1121764Y192218D01*
G02X1124266Y187294I1267J-2454D01*
G01X1116392Y183357D01*
G02X1113922Y188297I-1235J2470D01*
G37*
G36*
G01X1104199Y175318D02*
X1104034Y175388D01*
X1104032Y175384D01*
X1096156Y179322D01*
Y179330D01*
X1096053Y179387D01*
G02X1098557Y184525I1388J2503D01*
G01X1098722Y184455D01*
X1098724Y184459D01*
X1106601Y180521D01*
X1106599Y180517D01*
X1106767Y180418D01*
G02X1104199Y175318I-1453J-2465D01*
G37*
G36*
G01Y206814D02*
X1104034Y206884D01*
X1104032Y206880D01*
X1096156Y210818D01*
Y210826D01*
X1096053Y210883D01*
G02X1098557Y216021I1388J2503D01*
G01X1098722Y215951D01*
X1098724Y215955D01*
X1106601Y212017D01*
X1106599Y212013D01*
X1106767Y211914D01*
G02X1104199Y206814I-1453J-2465D01*
G37*
G36*
G01X1113922Y204045D02*
X1121763Y207965D01*
X1121764Y207966D01*
G02X1124266Y203042I1267J-2454D01*
G01X1116392Y199105D01*
G02X1113922Y204045I-1235J2470D01*
G37*
G36*
G01X1104199Y191066D02*
X1104034Y191136D01*
X1104032Y191132D01*
X1096156Y195070D01*
Y195078D01*
X1096053Y195135D01*
G02X1098557Y200273I1388J2503D01*
G01X1098722Y200203D01*
X1098724Y200207D01*
X1106601Y196269D01*
X1106599Y196265D01*
X1106767Y196166D01*
G02X1104199Y191066I-1453J-2465D01*
G37*
G36*
G01X1124320Y139943D02*
X1116446Y136006D01*
G02X1113868Y141160I-1289J2577D01*
G01X1121741Y145097D01*
G02X1124320Y139943I1290J-2577D01*
G37*
G36*
G01X1113922Y156801D02*
X1121763Y160721D01*
X1121764Y160722D01*
G02X1124266Y155798I1267J-2454D01*
G01X1116392Y151861D01*
G02X1113922Y156801I-1235J2470D01*
G37*
G36*
G01X1104199Y143822D02*
X1104034Y143892D01*
X1104032Y143888D01*
X1096156Y147826D01*
Y147834D01*
X1096053Y147891D01*
G02X1098557Y153029I1388J2503D01*
G01X1098722Y152959D01*
X1098724Y152963D01*
X1106601Y149025D01*
X1106599Y149021D01*
X1106767Y148922D01*
G02X1104199Y143822I-1453J-2465D01*
G37*
G36*
G01Y159570D02*
X1104034Y159640D01*
X1104032Y159636D01*
X1096156Y163574D01*
Y163582D01*
X1096053Y163639D01*
G02X1098557Y168777I1388J2503D01*
G01X1098722Y168707D01*
X1098724Y168711D01*
X1106601Y164773D01*
X1106599Y164769D01*
X1106767Y164670D01*
G02X1104199Y159570I-1453J-2465D01*
G37*
G36*
G01X1098730Y50609D02*
X1106604Y46672D01*
G02X1104026Y41518I-1289J-2577D01*
G01X1096195Y45434D01*
X1096194D01*
G02X1098730Y50609I1248J2597D01*
G37*
G36*
G01X1104199Y65082D02*
X1104034Y65152D01*
X1104032Y65148D01*
X1096156Y69086D01*
Y69094D01*
X1096053Y69151D01*
G02X1098557Y74289I1388J2503D01*
G01X1098722Y74219D01*
X1098724Y74223D01*
X1106601Y70285D01*
X1106599Y70281D01*
X1106767Y70182D01*
G02X1104199Y65082I-1453J-2465D01*
G37*
G36*
G01X1075250Y1413872D02*
X1070749D01*
G02X1070750Y1416876I1J1502D01*
G01X1075250D01*
G02Y1413872I0J-1502D01*
G37*
G36*
G01Y1406786D02*
X1070749D01*
G02X1070750Y1409788I1J1501D01*
G01X1075250D01*
G02Y1406786I0J-1501D01*
G37*
G36*
G01Y1399700D02*
X1070749D01*
G02X1070750Y1402702I1J1501D01*
G01X1075250D01*
G02Y1399700I0J-1501D01*
G37*
G36*
G01Y1392612D02*
X1070749D01*
G02X1070750Y1395616I1J1502D01*
G01X1075250D01*
G02Y1392612I0J-1502D01*
G37*
G36*
G01Y1385526D02*
X1070749D01*
G02X1070750Y1388530I1J1502D01*
G01X1075250D01*
G02Y1385526I0J-1502D01*
G37*
G36*
G01Y1378440D02*
X1070749D01*
G02X1070750Y1381442I1J1501D01*
G01X1075250D01*
G02Y1378440I0J-1501D01*
G37*
G36*
G01Y1328824D02*
X1070749D01*
G02X1070750Y1331846I1J1511D01*
G01X1075250D01*
G02Y1328824I0J-1511D01*
G37*
G36*
G01Y1293390D02*
X1070749D01*
G02X1070750Y1296414I1J1512D01*
G01X1075250D01*
G02Y1293390I0J-1512D01*
G37*
G36*
G01Y1300476D02*
X1070749D01*
G02X1070750Y1303500I1J1512D01*
G01X1075250D01*
G02Y1300476I0J-1512D01*
G37*
G36*
G01Y1307564D02*
X1070749D01*
G02X1070750Y1310586I1J1511D01*
G01X1075250D01*
G02Y1307564I0J-1511D01*
G37*
G36*
G01Y1314650D02*
X1070749D01*
G02X1070750Y1317672I1J1511D01*
G01X1075250D01*
G02Y1314650I0J-1511D01*
G37*
G36*
G01Y1321736D02*
X1070749D01*
G02X1070750Y1324760I1J1512D01*
G01X1075250D01*
G02Y1321736I0J-1512D01*
G37*
G36*
G01Y1229610D02*
X1070749D01*
G02X1070750Y1232634I1J1512D01*
G01X1075250D01*
G02Y1229610I0J-1512D01*
G37*
G36*
G01Y1236698D02*
X1070749D01*
G02X1070750Y1239720I1J1511D01*
G01X1075250D01*
G02Y1236698I0J-1511D01*
G37*
G36*
G01Y1243784D02*
X1070749D01*
G02X1070750Y1246806I1J1511D01*
G01X1075250D01*
G02Y1243784I0J-1511D01*
G37*
G36*
G01Y1208350D02*
X1070749D01*
G02X1070750Y1211374I1J1512D01*
G01X1075250D01*
G02Y1208350I0J-1512D01*
G37*
G36*
G01Y1215438D02*
X1070749D01*
G02X1070750Y1218460I1J1511D01*
G01X1075250D01*
G02Y1215438I0J-1511D01*
G37*
G36*
G01Y1222524D02*
X1070749D01*
G02X1070750Y1225546I1J1511D01*
G01X1075250D01*
G02Y1222524I0J-1511D01*
G37*
G36*
G01X956156Y708159D02*
X948315Y704239D01*
X948314Y704238D01*
G02X945812Y709162I-1267J2454D01*
G01X953686Y713099D01*
G02X956156Y708159I1235J-2470D01*
G37*
G36*
G01Y660915D02*
X948315Y656995D01*
X948314Y656994D01*
G02X945812Y661918I-1267J2454D01*
G01X953686Y665855D01*
G02X956156Y660915I1235J-2470D01*
G37*
G36*
G01Y692411D02*
X948315Y688491D01*
X948314Y688490D01*
G02X945812Y693414I-1267J2454D01*
G01X953686Y697351D01*
G02X956156Y692411I1235J-2470D01*
G37*
G36*
G01Y676663D02*
X948315Y672743D01*
X948314Y672742D01*
G02X945812Y677666I-1267J2454D01*
G01X953686Y681603D01*
G02X956156Y676663I1235J-2470D01*
G37*
G36*
G01X956210Y645060D02*
X948337Y641123D01*
G02X945758Y646277I-1290J2577D01*
G01X953632Y650214D01*
G02X956210Y645060I1289J-2577D01*
G37*
G36*
G01X945758Y630529D02*
X953631Y634466D01*
G02X956210Y629312I1290J-2577D01*
G01X948336Y625375D01*
G02X945758Y630529I-1289J2577D01*
G37*
G36*
G01Y614781D02*
X953631Y618718D01*
G02X956210Y613564I1290J-2577D01*
G01X948336Y609627D01*
G02X945758Y614781I-1289J2577D01*
G37*
G36*
G01X956210Y597816D02*
X948337Y593879D01*
G02X945758Y599033I-1290J2577D01*
G01X953632Y602970D01*
G02X956210Y597816I1289J-2577D01*
G37*
G36*
G01X956223Y503301D02*
X948392Y499386D01*
G02X945745Y504572I-1345J2582D01*
G01X953619Y508509D01*
G02X956223Y503301I1302J-2604D01*
G37*
G36*
G01X945745Y488824D02*
X953576Y492739D01*
G02X956223Y487553I1345J-2582D01*
G01X948349Y483616D01*
G02X945745Y488824I-1302J2604D01*
G37*
G36*
G01X945758Y473049D02*
X953631Y476986D01*
G02X956210Y471832I1290J-2577D01*
G01X948336Y467895D01*
G02X945758Y473049I-1289J2577D01*
G37*
G36*
G01X956210Y456084D02*
X948337Y452147D01*
G02X945758Y457301I-1290J2577D01*
G01X953632Y461238D01*
G02X956210Y456084I1289J-2577D01*
G37*
G36*
G01X945812Y314281D02*
X953653Y318201D01*
X953654Y318202D01*
G02X956156Y313278I1267J-2454D01*
G01X948282Y309341D01*
G02X945812Y314281I-1235J2470D01*
G37*
G36*
G01X956156Y329026D02*
X948315Y325106D01*
X948314Y325105D01*
G02X945812Y330029I-1267J2454D01*
G01X953686Y333966D01*
G02X956156Y329026I1235J-2470D01*
G37*
G36*
G01Y266034D02*
X948315Y262114D01*
X948314Y262113D01*
G02X945812Y267037I-1267J2454D01*
G01X953686Y270974D01*
G02X956156Y266034I1235J-2470D01*
G37*
G36*
G01X945812Y282785D02*
X953653Y286705D01*
X953654Y286706D01*
G02X956156Y281782I1267J-2454D01*
G01X948282Y277845D01*
G02X945812Y282785I-1235J2470D01*
G37*
G36*
G01Y298533D02*
X953653Y302453D01*
X953654Y302454D01*
G02X956156Y297530I1267J-2454D01*
G01X948282Y293593D01*
G02X945812Y298533I-1235J2470D01*
G37*
G36*
G01X956156Y218790D02*
X948315Y214870D01*
X948314Y214869D01*
G02X945812Y219793I-1267J2454D01*
G01X953686Y223730D01*
G02X956156Y218790I1235J-2470D01*
G37*
G36*
G01Y234538D02*
X948315Y230618D01*
X948314Y230617D01*
G02X945812Y235541I-1267J2454D01*
G01X953686Y239478D01*
G02X956156Y234538I1235J-2470D01*
G37*
G36*
G01Y250286D02*
X948315Y246366D01*
X948314Y246365D01*
G02X945812Y251289I-1267J2454D01*
G01X953686Y255226D01*
G02X956156Y250286I1235J-2470D01*
G37*
G36*
G01Y171546D02*
X948315Y167626D01*
X948314Y167625D01*
G02X945812Y172549I-1267J2454D01*
G01X953686Y176486D01*
G02X956156Y171546I1235J-2470D01*
G37*
G36*
G01Y187294D02*
X948315Y183374D01*
X948314Y183373D01*
G02X945812Y188297I-1267J2454D01*
G01X953686Y192234D01*
G02X956156Y187294I1235J-2470D01*
G37*
G36*
G01X945812Y204045D02*
X953653Y207965D01*
X953654Y207966D01*
G02X956156Y203042I1267J-2454D01*
G01X948282Y199105D01*
G02X945812Y204045I-1235J2470D01*
G37*
G36*
G01X945762Y141151D02*
X953636Y145088D01*
G02X956206Y139952I1285J-2568D01*
G01X948332Y136015D01*
G02X945762Y141151I-1285J2568D01*
G37*
G36*
G01X956156Y155798D02*
X948315Y151878D01*
X948314Y151877D01*
G02X945812Y156801I-1267J2454D01*
G01X953686Y160738D01*
G02X956156Y155798I1235J-2470D01*
G37*
G36*
G01X936089Y696183D02*
X935924Y696253D01*
X935922Y696249D01*
X928046Y700187D01*
Y700195D01*
X927943Y700252D01*
G02X930447Y705390I1388J2503D01*
G01X930612Y705320D01*
X930614Y705324D01*
X938491Y701386D01*
X938489Y701382D01*
X938657Y701283D01*
G02X936089Y696183I-1453J-2465D01*
G37*
G36*
G01Y680435D02*
X935924Y680505D01*
X935922Y680501D01*
X928046Y684439D01*
Y684447D01*
X927943Y684504D01*
G02X930447Y689642I1388J2503D01*
G01X930612Y689572D01*
X930614Y689576D01*
X938491Y685638D01*
X938489Y685634D01*
X938657Y685535D01*
G02X936089Y680435I-1453J-2465D01*
G37*
G36*
G01Y664687D02*
X935924Y664757D01*
X935922Y664753D01*
X928046Y668691D01*
Y668699D01*
X927943Y668756D01*
G02X930447Y673894I1388J2503D01*
G01X930612Y673824D01*
X930614Y673828D01*
X938491Y669890D01*
X938489Y669886D01*
X938657Y669787D01*
G02X936089Y664687I-1453J-2465D01*
G37*
G36*
G01Y648939D02*
X935924Y649009D01*
X935922Y649005D01*
X928046Y652943D01*
Y652951D01*
X927943Y653008D01*
G02X930447Y658146I1388J2503D01*
G01X930612Y658076D01*
X930614Y658080D01*
X938491Y654142D01*
X938489Y654138D01*
X938657Y654039D01*
G02X936089Y648939I-1453J-2465D01*
G37*
G36*
G01X935916Y601753D02*
X928085Y605669D01*
X928084D01*
G02X930620Y610844I1248J2597D01*
G01X938494Y606907D01*
G02X935916Y601753I-1289J-2577D01*
G37*
G36*
G01Y633249D02*
X928085Y637165D01*
X928084D01*
G02X930620Y642340I1248J2597D01*
G01X938494Y638403D01*
G02X935916Y633249I-1289J-2577D01*
G37*
G36*
G01Y617501D02*
X928085Y621417D01*
X928084D01*
G02X930620Y626592I1248J2597D01*
G01X938494Y622655D01*
G02X935916Y617501I-1289J-2577D01*
G37*
G36*
G01Y586005D02*
X928085Y589921D01*
X928084D01*
G02X930620Y595096I1248J2597D01*
G01X938494Y591159D01*
G02X935916Y586005I-1289J-2577D01*
G37*
G36*
G01Y507265D02*
X928085Y511181D01*
X928084D01*
G02X930620Y516356I1248J2597D01*
G01X938494Y512419D01*
G02X935916Y507265I-1289J-2577D01*
G37*
G36*
G01X936089Y538703D02*
X935924Y538773D01*
X935922Y538769D01*
X928046Y542707D01*
Y542715D01*
X927943Y542772D01*
G02X930447Y547910I1388J2503D01*
G01X930612Y547840D01*
X930614Y547844D01*
X938491Y543906D01*
X938489Y543902D01*
X938657Y543803D01*
G02X936089Y538703I-1453J-2465D01*
G37*
G36*
G01X935916Y491517D02*
X928085Y495433D01*
X928084D01*
G02X930620Y500608I1248J2597D01*
G01X938494Y496671D01*
G02X935916Y491517I-1289J-2577D01*
G37*
G36*
G01X930620Y484860D02*
X938451Y480944D01*
X938452D01*
G02X935916Y475769I-1248J-2597D01*
G01X928042Y479706D01*
G02X930620Y484860I1289J2577D01*
G37*
G36*
G01X935916Y460021D02*
X928085Y463937D01*
X928084D01*
G02X930620Y469112I1248J2597D01*
G01X938494Y465175D01*
G02X935916Y460021I-1289J-2577D01*
G37*
G36*
G01Y444273D02*
X928085Y448189D01*
X928084D01*
G02X930620Y453364I1248J2597D01*
G01X938494Y449427D01*
G02X935916Y444273I-1289J-2577D01*
G37*
G36*
G01X936089Y317050D02*
X935924Y317120D01*
X935922Y317116D01*
X928046Y321054D01*
Y321062D01*
X927943Y321119D01*
G02X930447Y326257I1388J2503D01*
G01X930612Y326187D01*
X930614Y326191D01*
X938491Y322253D01*
X938489Y322249D01*
X938657Y322150D01*
G02X936089Y317050I-1453J-2465D01*
G37*
G36*
G01Y269806D02*
X935924Y269876D01*
X935922Y269872D01*
X928046Y273810D01*
Y273818D01*
X927943Y273875D01*
G02X930447Y279013I1388J2503D01*
G01X930612Y278943D01*
X930614Y278947D01*
X938491Y275009D01*
X938489Y275005D01*
X938657Y274906D01*
G02X936089Y269806I-1453J-2465D01*
G37*
G36*
G01Y301302D02*
X935924Y301372D01*
X935922Y301368D01*
X928046Y305306D01*
Y305314D01*
X927943Y305371D01*
G02X930447Y310509I1388J2503D01*
G01X930612Y310439D01*
X930614Y310443D01*
X938491Y306505D01*
X938489Y306501D01*
X938657Y306402D01*
G02X936089Y301302I-1453J-2465D01*
G37*
G36*
G01Y285554D02*
X935924Y285624D01*
X935922Y285620D01*
X928046Y289558D01*
Y289566D01*
X927943Y289623D01*
G02X930447Y294761I1388J2503D01*
G01X930612Y294691D01*
X930614Y294695D01*
X938491Y290757D01*
X938489Y290753D01*
X938657Y290654D01*
G02X936089Y285554I-1453J-2465D01*
G37*
G36*
G01Y222562D02*
X935924Y222632D01*
X935922Y222628D01*
X928046Y226566D01*
Y226574D01*
X927943Y226631D01*
G02X930447Y231769I1388J2503D01*
G01X930612Y231699D01*
X930614Y231703D01*
X938491Y227765D01*
X938489Y227761D01*
X938657Y227662D01*
G02X936089Y222562I-1453J-2465D01*
G37*
G36*
G01Y254058D02*
X935924Y254128D01*
X935922Y254124D01*
X928045Y258062D01*
X928047Y258066D01*
X927879Y258165D01*
G02X930447Y263265I1453J2465D01*
G01X930612Y263195D01*
X930614Y263199D01*
X938490Y259261D01*
Y259253D01*
X938593Y259196D01*
G02X936089Y254058I-1388J-2503D01*
G37*
G36*
G01Y238310D02*
X935924Y238380D01*
X935922Y238376D01*
X928046Y242314D01*
Y242322D01*
X927943Y242379D01*
G02X930447Y247517I1388J2503D01*
G01X930612Y247447D01*
X930614Y247451D01*
X938491Y243513D01*
X938489Y243509D01*
X938657Y243410D01*
G02X936089Y238310I-1453J-2465D01*
G37*
G36*
G01Y175318D02*
X935924Y175388D01*
X935922Y175384D01*
X928046Y179322D01*
Y179330D01*
X927943Y179387D01*
G02X930447Y184525I1388J2503D01*
G01X930612Y184455D01*
X930614Y184459D01*
X938491Y180521D01*
X938489Y180517D01*
X938657Y180418D01*
G02X936089Y175318I-1453J-2465D01*
G37*
G36*
G01Y191066D02*
X935924Y191136D01*
X935922Y191132D01*
X928046Y195070D01*
Y195078D01*
X927943Y195135D01*
G02X930447Y200273I1388J2503D01*
G01X930612Y200203D01*
X930614Y200207D01*
X938491Y196269D01*
X938489Y196265D01*
X938657Y196166D01*
G02X936089Y191066I-1453J-2465D01*
G37*
G36*
G01Y206814D02*
X935924Y206884D01*
X935922Y206880D01*
X928046Y210818D01*
Y210826D01*
X927943Y210883D01*
G02X930447Y216021I1388J2503D01*
G01X930612Y215951D01*
X930614Y215955D01*
X938491Y212017D01*
X938489Y212013D01*
X938657Y211914D01*
G02X936089Y206814I-1453J-2465D01*
G37*
G36*
G01Y159570D02*
X935924Y159640D01*
X935922Y159636D01*
X928046Y163574D01*
Y163582D01*
X927943Y163639D01*
G02X930447Y168777I1388J2503D01*
G01X930612Y168707D01*
X930614Y168711D01*
X938491Y164773D01*
X938489Y164769D01*
X938657Y164670D01*
G02X936089Y159570I-1453J-2465D01*
G37*
G36*
G01Y143822D02*
X935924Y143892D01*
X935922Y143888D01*
X928046Y147826D01*
Y147834D01*
X927943Y147891D01*
G02X930447Y153029I1388J2503D01*
G01X930612Y152959D01*
X930614Y152963D01*
X938491Y149025D01*
X938489Y149021D01*
X938657Y148922D01*
G02X936089Y143822I-1453J-2465D01*
G37*
G36*
G01X930620Y50609D02*
X938494Y46672D01*
G02X935916Y41518I-1289J-2577D01*
G01X928085Y45434D01*
X928084D01*
G02X930620Y50609I1248J2597D01*
G37*
G36*
G01X936089Y65082D02*
X935924Y65152D01*
X935922Y65148D01*
X928046Y69086D01*
Y69094D01*
X927943Y69151D01*
G02X930447Y74289I1388J2503D01*
G01X930612Y74219D01*
X930614Y74223D01*
X938491Y70285D01*
X938489Y70281D01*
X938657Y70182D01*
G02X936089Y65082I-1453J-2465D01*
G37*
G36*
G01X878540Y1646457D02*
Y1640944D01*
G02X874216Y1640945I-2162J1D01*
G01Y1646457D01*
G02X878540I2162J0D01*
G37*
G36*
G01X871454Y1636221D02*
Y1630708D01*
G02X867130Y1630709I-2162J1D01*
G01Y1636221D01*
G02X871454I2162J0D01*
G37*
G36*
G01X864366Y1646457D02*
Y1640944D01*
G02X860044Y1640945I-2161J1D01*
G01Y1646457D01*
G02X864366I2161J0D01*
G37*
G36*
G01X857280Y1636221D02*
Y1630708D01*
G02X852956Y1630709I-2162J1D01*
G01Y1636221D01*
G02X857280I2162J0D01*
G37*
G36*
G01X850194Y1646457D02*
Y1640944D01*
G02X845870Y1640945I-2162J1D01*
G01Y1646457D01*
G02X850194I2162J0D01*
G37*
G36*
G01X878540Y1603937D02*
Y1598424D01*
G02X874216Y1598425I-2162J1D01*
G01Y1603937D01*
G02X878540I2162J0D01*
G37*
G36*
G01X871454Y1607874D02*
Y1602362D01*
G02X867130Y1602363I-2162J1D01*
G01Y1607874D01*
G02X871454I2162J0D01*
G37*
G36*
G01X864366Y1603937D02*
Y1598424D01*
G02X860044Y1598425I-2161J1D01*
G01Y1603937D01*
G02X864366I2161J0D01*
G37*
G36*
G01X857280Y1607874D02*
Y1602362D01*
G02X852956Y1602363I-2162J1D01*
G01Y1607874D01*
G02X857280I2162J0D01*
G37*
G36*
G01X850194Y1603937D02*
Y1598424D01*
G02X845870Y1598425I-2162J1D01*
G01Y1603937D01*
G02X850194I2162J0D01*
G37*
G36*
G01X843106Y1636221D02*
Y1630708D01*
G02X838784Y1630709I-2161J1D01*
G01Y1636221D01*
G02X843106I2161J0D01*
G37*
G36*
G01X836020Y1646457D02*
Y1640944D01*
G02X831698Y1640945I-2161J1D01*
G01Y1646457D01*
G02X836020I2161J0D01*
G37*
G36*
G01X828934Y1636221D02*
Y1630708D01*
G02X824610Y1630709I-2162J1D01*
G01Y1636221D01*
G02X828934I2162J0D01*
G37*
G36*
G01Y1622048D02*
Y1616535D01*
G02X824610Y1616536I-2162J1D01*
G01Y1622048D01*
G02X828934I2162J0D01*
G37*
G36*
G01X843106Y1607874D02*
Y1602362D01*
G02X838784Y1602363I-2161J1D01*
G01Y1607874D01*
G02X843106I2161J0D01*
G37*
G36*
G01X836020Y1603937D02*
Y1598424D01*
G02X831698Y1598425I-2161J1D01*
G01Y1603937D01*
G02X836020I2161J0D01*
G37*
G36*
G01X828934Y1607874D02*
Y1602362D01*
G02X824610Y1602363I-2162J1D01*
G01Y1607874D01*
G02X828934I2162J0D01*
G37*
G36*
G01X566532Y91930D02*
Y86417D01*
G02X562208Y86418I-2162J1D01*
G01Y91930D01*
G02X566532I2162J0D01*
G37*
G36*
G01Y77756D02*
Y72244D01*
G02X562208Y72245I-2162J1D01*
G01Y77756D01*
G02X566532I2162J0D01*
G37*
G36*
G01Y120276D02*
Y114763D01*
G02X562208Y114764I-2162J1D01*
G01Y120276D01*
G02X566532I2162J0D01*
G37*
G36*
G01X519688Y72245D02*
Y77757D01*
G02X524012Y77756I2162J-1D01*
G01Y72245D01*
G02X519688I-2162J0D01*
G37*
G36*
G01X516926Y87993D02*
Y82480D01*
G02X512602Y82481I-2162J1D01*
G01Y87993D01*
G02X516926I2162J0D01*
G37*
G36*
G01X524012Y91930D02*
Y86417D01*
G02X519688Y86418I-2162J1D01*
G01Y91930D01*
G02X524012I2162J0D01*
G37*
G36*
G01X531098Y87993D02*
Y82480D01*
G02X526776Y82481I-2161J1D01*
G01Y87993D01*
G02X531098I2161J0D01*
G37*
G36*
G01X538186Y91930D02*
Y86417D01*
G02X533862Y86418I-2162J1D01*
G01Y91930D01*
G02X538186I2162J0D01*
G37*
G36*
G01Y77756D02*
Y72244D01*
G02X533862Y72245I-2162J1D01*
G01Y77756D01*
G02X538186I2162J0D01*
G37*
G36*
G01Y120276D02*
Y114763D01*
G02X533862Y114764I-2162J1D01*
G01Y120276D01*
G02X538186I2162J0D01*
G37*
G36*
G01X545272Y87993D02*
Y82480D01*
G02X540948Y82481I-2162J1D01*
G01Y87993D01*
G02X545272I2162J0D01*
G37*
G36*
G01X552358Y91930D02*
Y86417D01*
G02X548036Y86418I-2161J1D01*
G01Y91930D01*
G02X552358I2161J0D01*
G37*
G36*
G01X559444Y87993D02*
Y82480D01*
G02X555122Y82481I-2161J1D01*
G01Y87993D01*
G02X559444I2161J0D01*
G37*
G36*
G01X552358Y77756D02*
Y72244D01*
G02X548036Y72245I-2161J1D01*
G01Y77756D01*
G02X552358I2161J0D01*
G37*
G36*
G01X516926Y73819D02*
Y68306D01*
G02X512602Y68307I-2162J1D01*
G01Y73819D01*
G02X516926I2162J0D01*
G37*
G36*
G01X531098D02*
Y68306D01*
G02X526776Y68307I-2161J1D01*
G01Y73819D01*
G02X531098I2161J0D01*
G37*
G36*
G01X545272D02*
Y68306D01*
G02X540948Y68307I-2162J1D01*
G01Y73819D01*
G02X545272I2162J0D01*
G37*
G36*
G01X559444D02*
Y68306D01*
G02X555122Y68307I-2161J1D01*
G01Y73819D01*
G02X559444I2161J0D01*
G37*
G36*
G01X481492Y77756D02*
Y72244D01*
G02X477170Y72245I-2161J1D01*
G01Y77756D01*
G02X481492I2161J0D01*
G37*
G36*
G01X467318Y91930D02*
Y86417D01*
G02X462996Y86418I-2161J1D01*
G01Y91930D01*
G02X467318I2161J0D01*
G37*
G36*
G01X474406Y87993D02*
Y82480D01*
G02X470082Y82481I-2162J1D01*
G01Y87993D01*
G02X474406I2162J0D01*
G37*
G36*
G01X481492Y91930D02*
Y86417D01*
G02X477170Y86418I-2161J1D01*
G01Y91930D01*
G02X481492I2161J0D01*
G37*
G36*
G01X467318Y77756D02*
Y72244D01*
G02X462996Y72245I-2161J1D01*
G01Y77756D01*
G02X467318I2161J0D01*
G37*
G36*
G01X477160Y114764D02*
Y120277D01*
G02X481502Y120276I2171J-1D01*
G01Y114764D01*
G02X477160I-2171J0D01*
G37*
G36*
G01X474406Y73819D02*
Y68306D01*
G02X470082Y68307I-2162J1D01*
G01Y73819D01*
G02X474406I2162J0D01*
G37*
G36*
G01X438972Y77756D02*
Y72244D01*
G02X434650Y72245I-2161J1D01*
G01Y77756D01*
G02X438972I2161J0D01*
G37*
G36*
G01X431886Y87993D02*
Y82480D01*
G02X427562Y82481I-2162J1D01*
G01Y87993D01*
G02X431886I2162J0D01*
G37*
G36*
G01X438972Y91930D02*
Y86417D01*
G02X434650Y86418I-2161J1D01*
G01Y91930D01*
G02X438972I2161J0D01*
G37*
G36*
G01X446060Y87993D02*
Y82480D01*
G02X441736Y82481I-2162J1D01*
G01Y87993D01*
G02X446060I2162J0D01*
G37*
G36*
G01X453146Y91930D02*
Y86417D01*
G02X448822Y86418I-2162J1D01*
G01Y91930D01*
G02X453146I2162J0D01*
G37*
G36*
G01X460232Y87993D02*
Y82480D01*
G02X455910Y82481I-2161J1D01*
G01Y87993D01*
G02X460232I2161J0D01*
G37*
G36*
G01X453146Y77756D02*
Y72244D01*
G02X448822Y72245I-2162J1D01*
G01Y77756D01*
G02X453146I2162J0D01*
G37*
G36*
G01X460232Y116339D02*
Y110826D01*
G02X455910Y110827I-2161J1D01*
G01Y116339D01*
G02X460232I2161J0D01*
G37*
G36*
G01X431886Y73819D02*
Y68306D01*
G02X427562Y68307I-2162J1D01*
G01Y73819D01*
G02X431886I2162J0D01*
G37*
G36*
G01X446060D02*
Y68306D01*
G02X441736Y68307I-2162J1D01*
G01Y73819D01*
G02X446060I2162J0D01*
G37*
G36*
G01X460232D02*
Y68306D01*
G02X455910Y68307I-2161J1D01*
G01Y73819D01*
G02X460232I2161J0D01*
G37*
G36*
G01X1898061Y1091290D02*
X1898062Y1091293D01*
Y1095715D01*
X1898061Y1095718D01*
G02X1901065I1502J36D01*
G01X1901064Y1095715D01*
Y1091293D01*
X1901065Y1091290D01*
G02X1898061I-1502J-36D01*
G37*
G36*
G01X1776852Y1095718D02*
Y1091290D01*
G02X1773848I-1502J-36D01*
G01Y1095718D01*
G02X1776852I1502J36D01*
G37*
G36*
G01X1652640D02*
Y1091290D01*
G02X1649636I-1502J-36D01*
G01Y1095718D01*
G02X1652640I1502J36D01*
G37*
G36*
G01X1525423Y1091290D02*
X1525424Y1091293D01*
Y1095715D01*
X1525423Y1095718D01*
G02X1528427I1502J36D01*
G01X1528426Y1095715D01*
Y1091293D01*
X1528427Y1091290D01*
G02X1525423I-1502J-36D01*
G37*
G36*
G01X1401211D02*
X1401212Y1091293D01*
Y1095715D01*
X1401211Y1095718D01*
G02X1404215I1502J36D01*
G01X1404214Y1095715D01*
Y1091293D01*
X1404215Y1091290D01*
G02X1401211I-1502J-36D01*
G37*
G36*
G01X1280002Y1095718D02*
Y1091290D01*
G02X1276998I-1502J-36D01*
G01Y1095718D01*
G02X1280002I1502J36D01*
G37*
G36*
G01X747549Y1091290D02*
X747550Y1091293D01*
Y1095715D01*
X747549Y1095718D01*
G02X750553I1502J36D01*
G01X750552Y1095715D01*
Y1091293D01*
X750553Y1091290D01*
G02X747549I-1502J-36D01*
G37*
G36*
G01X626340Y1095718D02*
Y1091290D01*
G02X623336I-1502J-36D01*
G01Y1095718D01*
G02X626340I1502J36D01*
G37*
G36*
G01X499123Y1091290D02*
X499124Y1091293D01*
Y1095715D01*
X499123Y1095718D01*
G02X502127I1502J36D01*
G01X502126Y1095715D01*
Y1091293D01*
X502127Y1091290D01*
G02X499123I-1502J-36D01*
G37*
G36*
G01X374911D02*
X374912Y1091293D01*
Y1095715D01*
X374911Y1095718D01*
G02X377915I1502J36D01*
G01X377914Y1095715D01*
Y1091293D01*
X377915Y1091290D01*
G02X374911I-1502J-36D01*
G37*
G36*
G01X253702Y1095718D02*
Y1091290D01*
G02X250698I-1502J-36D01*
G01Y1095718D01*
G02X253702I1502J36D01*
G37*
G36*
G01X129490D02*
Y1091290D01*
G02X126486I-1502J-36D01*
G01Y1095718D01*
G02X129490I1502J36D01*
G37*
G36*
G01X1879361Y1076290D02*
X1879362Y1076293D01*
Y1080715D01*
X1879361Y1080718D01*
G02X1882365I1502J36D01*
G01X1882364Y1080715D01*
Y1076293D01*
X1882365Y1076290D01*
G02X1879361I-1502J-36D01*
G37*
G36*
G01X1758152Y1080718D02*
Y1076290D01*
G02X1755148I-1502J-36D01*
G01Y1080718D01*
G02X1758152I1502J36D01*
G37*
G36*
G01X1633940D02*
Y1076290D01*
G02X1630936I-1502J-36D01*
G01Y1080718D01*
G02X1633940I1502J36D01*
G37*
G36*
G01X1506723Y1076290D02*
X1506724Y1076293D01*
Y1080715D01*
X1506723Y1080718D01*
G02X1509727I1502J36D01*
G01X1509726Y1080715D01*
Y1076293D01*
X1509727Y1076290D01*
G02X1506723I-1502J-36D01*
G37*
G36*
G01X1382511D02*
X1382512Y1076293D01*
Y1080715D01*
X1382511Y1080718D01*
G02X1385515I1502J36D01*
G01X1385514Y1080715D01*
Y1076293D01*
X1385515Y1076290D01*
G02X1382511I-1502J-36D01*
G37*
G36*
G01X1898061Y638534D02*
X1898062Y638537D01*
Y642959D01*
X1898061Y642962D01*
G02X1901065I1502J36D01*
G01X1901064Y642959D01*
Y638537D01*
X1901065Y638534D01*
G02X1898061I-1502J-36D01*
G37*
G36*
G01X1726852Y642962D02*
Y638534D01*
G02X1723848I-1502J-36D01*
G01Y642962D01*
G02X1726852I1502J36D01*
G37*
G36*
G01X1652640D02*
Y638534D01*
G02X1649636I-1502J-36D01*
G01Y642962D01*
G02X1652640I1502J36D01*
G37*
G36*
G01X1525423Y638534D02*
X1525424Y638537D01*
Y642959D01*
X1525423Y642962D01*
G02X1528427I1502J36D01*
G01X1528426Y642959D01*
Y638537D01*
X1528427Y638534D01*
G02X1525423I-1502J-36D01*
G37*
G36*
G01X1401211D02*
X1401212Y638537D01*
Y642959D01*
X1401211Y642962D01*
G02X1404215I1502J36D01*
G01X1404214Y642959D01*
Y638537D01*
X1404215Y638534D01*
G02X1401211I-1502J-36D01*
G37*
G36*
G01X1280002Y642962D02*
Y638534D01*
G02X1276998I-1502J-36D01*
G01Y642962D01*
G02X1280002I1502J36D01*
G37*
G36*
G01X747549Y638534D02*
X747550Y638537D01*
Y642959D01*
X747549Y642962D01*
G02X750553I1502J36D01*
G01X750552Y642959D01*
Y638537D01*
X750553Y638534D01*
G02X747549I-1502J-36D01*
G37*
G36*
G01X626340Y642962D02*
Y638534D01*
G02X623336I-1502J-36D01*
G01Y642962D01*
G02X626340I1502J36D01*
G37*
G36*
G01X499123Y638534D02*
X499124Y638537D01*
Y642959D01*
X499123Y642962D01*
G02X502127I1502J36D01*
G01X502126Y642959D01*
Y638537D01*
X502127Y638534D01*
G02X499123I-1502J-36D01*
G37*
G36*
G01X374911D02*
X374912Y638537D01*
Y642959D01*
X374911Y642962D01*
G02X377915I1502J36D01*
G01X377914Y642959D01*
Y638537D01*
X377915Y638534D01*
G02X374911I-1502J-36D01*
G37*
G36*
G01X253702Y642962D02*
Y638534D01*
G02X250698I-1502J-36D01*
G01Y642962D01*
G02X253702I1502J36D01*
G37*
G36*
G01X129490D02*
Y638534D01*
G02X126486I-1502J-36D01*
G01Y642962D01*
G02X129490I1502J36D01*
G37*
G36*
G01X1879361Y623534D02*
X1879362Y623537D01*
Y627959D01*
X1879361Y627962D01*
G02X1882365I1502J36D01*
G01X1882364Y627959D01*
Y623537D01*
X1882365Y623534D01*
G02X1879361I-1502J-36D01*
G37*
G36*
G01X1733152Y627962D02*
Y623534D01*
G02X1730148I-1502J-36D01*
G01Y627962D01*
G02X1733152I1502J36D01*
G37*
G36*
G01X1633940D02*
Y623534D01*
G02X1630936I-1502J-36D01*
G01Y627962D01*
G02X1633940I1502J36D01*
G37*
G36*
G01X1506723Y623534D02*
X1506724Y623537D01*
Y627959D01*
X1506723Y627962D01*
G02X1509727I1502J36D01*
G01X1509726Y627959D01*
Y623537D01*
X1509727Y623534D01*
G02X1506723I-1502J-36D01*
G37*
G36*
G01X1382511D02*
X1382512Y623537D01*
Y627959D01*
X1382511Y627962D01*
G02X1385515I1502J36D01*
G01X1385514Y627959D01*
Y623537D01*
X1385515Y623534D01*
G02X1382511I-1502J-36D01*
G37*
G36*
G01X1261302Y627962D02*
Y623534D01*
G02X1258298I-1502J-36D01*
G01Y627962D01*
G02X1261302I1502J36D01*
G37*
G36*
G01X1898061Y185778D02*
X1898062Y185781D01*
Y190203D01*
X1898061Y190206D01*
G02X1901065I1502J36D01*
G01X1901064Y190203D01*
Y185781D01*
X1901065Y185778D01*
G02X1898061I-1502J-36D01*
G37*
G36*
G01X1776852Y190206D02*
Y185778D01*
G02X1773848I-1502J-36D01*
G01Y190206D01*
G02X1776852I1502J36D01*
G37*
G36*
G01X1652640D02*
Y185778D01*
G02X1649636I-1502J-36D01*
G01Y190206D01*
G02X1652640I1502J36D01*
G37*
G36*
G01X1525423Y185778D02*
X1525424Y185781D01*
Y190203D01*
X1525423Y190206D01*
G02X1528427I1502J36D01*
G01X1528426Y190203D01*
Y185781D01*
X1528427Y185778D01*
G02X1525423I-1502J-36D01*
G37*
G36*
G01X747549D02*
X747550Y185781D01*
Y190203D01*
X747549Y190206D01*
G02X750553I1502J36D01*
G01X750552Y190203D01*
Y185781D01*
X750553Y185778D01*
G02X747549I-1502J-36D01*
G37*
G36*
G01X626340Y190206D02*
Y185778D01*
G02X623336I-1502J-36D01*
G01Y190206D01*
G02X626340I1502J36D01*
G37*
G36*
G01X499123Y185778D02*
X499124Y185781D01*
Y190203D01*
X499123Y190206D01*
G02X502127I1502J36D01*
G01X502126Y190203D01*
Y185781D01*
X502127Y185778D01*
G02X499123I-1502J-36D01*
G37*
G36*
G01X374911D02*
X374912Y185781D01*
Y190203D01*
X374911Y190206D01*
G02X377915I1502J36D01*
G01X377914Y190203D01*
Y185781D01*
X377915Y185778D01*
G02X374911I-1502J-36D01*
G37*
G36*
G01X253702Y190206D02*
Y185778D01*
G02X250698I-1502J-36D01*
G01Y190206D01*
G02X253702I1502J36D01*
G37*
G36*
G01X129490D02*
Y185778D01*
G02X126486I-1502J-36D01*
G01Y190206D01*
G02X129490I1502J36D01*
G37*
G36*
G01X1270436Y184325D02*
X1270439Y184324D01*
X1274861D01*
X1274864Y184325D01*
G02Y181321I36J-1502D01*
G01X1274861Y181322D01*
X1270439D01*
X1270436Y181321D01*
G02Y184325I-36J1502D01*
G37*
G36*
G01X1511414Y180198D02*
X1506986D01*
G02Y183202I-36J1502D01*
G01X1511414D01*
G02Y180198I36J-1502D01*
G37*
G36*
G01X1879361Y170778D02*
X1879362Y170781D01*
Y175203D01*
X1879361Y175206D01*
G02X1882365I1502J36D01*
G01X1882364Y175203D01*
Y170781D01*
X1882365Y170778D01*
G02X1879361I-1502J-36D01*
G37*
G36*
G01X1758152Y175206D02*
Y170778D01*
G02X1755148I-1502J-36D01*
G01Y175206D01*
G02X1758152I1502J36D01*
G37*
G36*
G01X1633940D02*
Y170778D01*
G02X1630936I-1502J-36D01*
G01Y175206D01*
G02X1633940I1502J36D01*
G37*
G36*
G01X1256786Y169325D02*
X1256789Y169324D01*
X1261211D01*
X1261214Y169325D01*
G02Y166321I36J-1502D01*
G01X1261211Y166322D01*
X1256789D01*
X1256786Y166321D01*
G02Y169325I-36J1502D01*
G37*
G36*
G01X970474Y-46450D02*
Y-70079D01*
G02X919290I-25592J0D01*
G01Y-46456D01*
G02X960345Y-26064I25592J0D01*
G03X960986Y-25741I241J319D01*
G02X970115Y-39262I14801J151D01*
G03X969576Y-39736I-153J-369D01*
G02X970474Y-46450I-24694J-6720D01*
G37*
G36*
G01X558368Y829921D02*
G02I-55120J0D01*
G37*
G36*
G01X1729038D02*
G02I-55121J0D01*
G37*
G54D56*
X111024Y153681D03*
Y606437D03*
Y1059193D03*
X235236Y153681D03*
Y606437D03*
Y1059193D03*
X359449Y153681D03*
Y606437D03*
Y1059193D03*
X483661Y153681D03*
Y606437D03*
Y1059193D03*
X607874Y153681D03*
Y606437D03*
Y1059193D03*
X732087Y153681D03*
Y606437D03*
Y1059193D03*
X949902Y-115157D03*
X1281693Y153681D03*
Y606437D03*
Y1059193D03*
X1405906Y153681D03*
Y606437D03*
Y1059193D03*
X1530118Y153681D03*
Y606437D03*
Y1059193D03*
X1654331Y153681D03*
Y606437D03*
Y1059193D03*
X1778543Y153681D03*
Y606437D03*
Y1059193D03*
X1902756Y153681D03*
Y606437D03*
Y1059193D03*
G54D57*
X111024Y302303D03*
Y755059D03*
Y1207815D03*
X235236Y302303D03*
Y755059D03*
Y1207815D03*
X359449Y302303D03*
Y755059D03*
Y1207815D03*
X483661Y302303D03*
Y755059D03*
Y1207815D03*
X607874Y302303D03*
Y755059D03*
Y1207815D03*
X732087Y302303D03*
Y755059D03*
Y1207815D03*
X1098524Y-115157D03*
X1281693Y302303D03*
Y755059D03*
Y1207815D03*
X1405906Y302303D03*
Y755059D03*
Y1207815D03*
X1530118Y302303D03*
Y755059D03*
Y1207815D03*
X1654331Y302303D03*
Y755059D03*
Y1207815D03*
X1778543Y302303D03*
Y755059D03*
Y1207815D03*
X1902756Y302303D03*
Y755059D03*
Y1207815D03*
G54D58*
X79000Y1301900D03*
X1826700Y77600D03*
X1908500Y1346800D03*
G54D55*
X80019Y51968D03*
X127263Y20472D03*
X631200Y51968D03*
X678444Y20472D03*
X1250689Y51969D03*
X1297933Y20472D03*
X1801870Y51969D03*
X1849114Y20472D03*
G54D62*
X942126Y58465D03*
Y346457D03*
Y437598D03*
Y725590D03*
X1110236Y58465D03*
Y346457D03*
Y437598D03*
Y725590D03*
G54D59*
X173228Y1114173D03*
X670079D03*
X1343700D03*
X1840551D03*
G54D61*
X496653Y80906D03*
X1465157D03*
G54D54*
X103642Y36220D03*
X173228Y1062992D03*
X421653Y1141732D03*
X654822Y36220D03*
X670079Y1062992D03*
X1274311Y36220D03*
X1343701Y1062992D03*
X1592126Y1141732D03*
X1825492Y36220D03*
X1840551Y1062992D03*
G54D64*
X1903346Y803937D03*
G54D53*
X31496Y882677D03*
X168307Y646457D03*
X660236D03*
X718110Y820866D03*
X904921Y564961D03*
X1366142Y646457D03*
X1462992Y866929D03*
X1602756Y646457D03*
X1894685Y21654D03*
G54D63*
X975788Y564961D03*
G54D60*
X496654Y110551D03*
X1465158D03*
G54D47*
X1797933Y1282666D03*
Y829910D03*
Y377154D03*
X1549901Y1282666D03*
Y829910D03*
Y377154D03*
X796457Y735444D03*
Y263003D03*
X627263Y1282666D03*
Y829910D03*
Y377154D03*
X131201Y1282666D03*
Y377154D03*
G54D50*
X1102113Y1394115D03*
X1098176Y1401201D03*
X1102113Y1351595D03*
X1098176Y1330335D03*
Y1372855D03*
X1126522Y1330335D03*
X1130459Y1351595D03*
X1102113Y1280729D03*
X1098176Y1301989D03*
X1102113Y1309075D03*
Y1323249D03*
X1130459Y1280729D03*
X1098176Y1259469D03*
Y1231123D03*
X1102113Y1238209D03*
X1126522Y1259469D03*
X1098176Y1188603D03*
X1102113Y1209863D03*
X1098176Y1216949D03*
X1126522Y1188603D03*
X1102113Y1167343D03*
X1098176Y1160257D03*
G54D48*
X1301870Y1282666D03*
Y829910D03*
Y377154D03*
X1181890Y1559854D03*
X1181870Y969280D03*
X1181890Y555917D03*
X961418Y1429932D03*
Y1087413D03*
X379232Y1282666D03*
Y829910D03*
Y377154D03*
X131200Y829910D03*
G54D52*
X1126522Y1401201D03*
X1130459Y1394115D03*
X1126522Y1372855D03*
X1130459Y1323249D03*
Y1309075D03*
X1126522Y1301989D03*
X1130459Y1238209D03*
X1126522Y1231123D03*
Y1216949D03*
X1130459Y1209863D03*
Y1167343D03*
X1126522Y1160257D03*
X1098176Y1002765D03*
X1102113Y1024025D03*
X1098176Y1031111D03*
X1126522D03*
X1130459Y1024025D03*
X1126522Y1002765D03*
G54D49*
X1102113Y1379942D03*
X1098176Y1387028D03*
X1102113Y1408288D03*
Y1365768D03*
X1098176Y1358682D03*
Y1344508D03*
X1102113Y1337422D03*
X1130459D03*
X1126522Y1344508D03*
Y1358682D03*
X1130459Y1365768D03*
X1098176Y1287816D03*
X1102113Y1294902D03*
X1098176Y1316162D03*
Y1273642D03*
X1102113Y1266556D03*
Y1252382D03*
X1098176Y1245296D03*
X1126522D03*
X1130459Y1252382D03*
Y1266556D03*
X1126522Y1273642D03*
X1102113Y1195690D03*
Y1181516D03*
X1098176Y1202776D03*
X1102113Y1224036D03*
X1130459Y1181516D03*
Y1195690D03*
X1098176Y1174430D03*
X1126522D03*
X1116286Y1038198D03*
G54D51*
X1130459Y1408288D03*
X1126522Y1387028D03*
X1130459Y1379942D03*
X1126522Y1316162D03*
X1130459Y1294902D03*
X1126522Y1287816D03*
X1130459Y1224036D03*
X1126522Y1202776D03*
X1102113Y1038198D03*
X1130459D03*
X1098176Y988592D03*
X1102113Y995678D03*
Y1009852D03*
X1098176Y1016938D03*
X1126522D03*
X1130459Y1009852D03*
Y995678D03*
X1126522Y988592D03*
G54D24*
X127988Y190242D03*
Y185742D03*
Y638498D03*
Y642998D03*
Y1091254D03*
Y1095754D03*
X252200Y190242D03*
Y185742D03*
Y638498D03*
Y642998D03*
Y1091254D03*
Y1095754D03*
X376413Y190242D03*
Y185742D03*
Y638498D03*
Y642998D03*
Y1091254D03*
Y1095754D03*
X500625Y190242D03*
Y185742D03*
Y638498D03*
Y642998D03*
Y1091254D03*
Y1095754D03*
X624838Y190242D03*
Y185742D03*
Y638498D03*
Y642998D03*
Y1091254D03*
Y1095754D03*
X749051Y190242D03*
Y185742D03*
Y638498D03*
Y642998D03*
Y1091254D03*
Y1095754D03*
X1070750Y1224035D03*
X1075250D03*
X1070750Y1209862D03*
X1075250D03*
X1070750Y1216949D03*
X1075250D03*
X1070750Y1231122D03*
X1075250D03*
X1070750Y1238209D03*
X1075250D03*
X1070750Y1245295D03*
X1075250D03*
X1070750Y1301988D03*
X1075250D03*
X1070750Y1309075D03*
X1075250D03*
X1070750Y1316161D03*
X1075250D03*
X1070750Y1323248D03*
X1075250D03*
X1070750Y1294902D03*
X1075250D03*
X1070750Y1330335D03*
X1075250D03*
X1070750Y1387028D03*
X1075250D03*
X1070750Y1394114D03*
X1075250D03*
X1070750Y1401201D03*
X1075250D03*
X1070750Y1408287D03*
X1075250D03*
X1070750Y1415374D03*
X1075250D03*
X1070750Y1379941D03*
X1075250D03*
X1274900Y182823D03*
X1270400D03*
X1261250Y167823D03*
X1256750D03*
X1278500Y638498D03*
Y642998D03*
X1259800Y627998D03*
Y623498D03*
Y1080754D03*
Y1076254D03*
X1278500Y1091254D03*
Y1095754D03*
X1402713Y185742D03*
Y190242D03*
X1380963Y167823D03*
X1385463D03*
X1402713Y638498D03*
Y642998D03*
X1384013Y627998D03*
Y623498D03*
Y1080754D03*
Y1076254D03*
X1402713Y1091254D03*
Y1095754D03*
X1511450Y181700D03*
X1506950D03*
X1508225Y627998D03*
Y623498D03*
Y1080754D03*
Y1076254D03*
X1526925Y185742D03*
Y190242D03*
Y638498D03*
Y642998D03*
Y1091254D03*
Y1095754D03*
X1651138Y185742D03*
Y190242D03*
X1632438Y175242D03*
Y170742D03*
X1651138Y638498D03*
Y642998D03*
X1632438Y627998D03*
Y623498D03*
Y1080754D03*
Y1076254D03*
X1651138Y1091254D03*
Y1095754D03*
X1756650Y175242D03*
Y170742D03*
X1725350Y638498D03*
Y642998D03*
X1731650Y627998D03*
Y623498D03*
X1756650Y1080754D03*
Y1076254D03*
X1775350Y185742D03*
Y190242D03*
Y1091254D03*
Y1095754D03*
X1899563Y185742D03*
Y190242D03*
X1880863Y175242D03*
Y170742D03*
X1899563Y638498D03*
Y642998D03*
X1880863Y627998D03*
Y623498D03*
Y1080754D03*
Y1076254D03*
X1899563Y1091254D03*
Y1095754D03*
G54D43*
X1039845Y1467746D03*
X1026345D03*
X1030845D03*
X1035345D03*
X1039845Y1463246D03*
X1026345D03*
X1030845D03*
X1035345D03*
X1005400Y1463157D03*
X1000900D03*
X996400D03*
X1009900D03*
X1005400Y1467657D03*
X1000900D03*
X996400D03*
X1009900D03*
X1035345Y1476746D03*
X1030845D03*
X1026345D03*
X1039845D03*
Y1472246D03*
X1026345D03*
X1030845D03*
X1035345D03*
X1005400Y1472157D03*
X1000900D03*
X996400D03*
X1009900D03*
Y1476657D03*
X1005400D03*
X1000900D03*
X996400D03*
X1023583Y1489593D03*
X995783D03*
X1000500Y1511400D03*
X1036578Y1511210D03*
X1014690Y1511178D03*
X1010190D03*
X1005690D03*
X1031790Y1511078D03*
X1027290D03*
X1019600Y1511100D03*
X1023583Y1501593D03*
Y1507593D03*
Y1495593D03*
X995783D03*
Y1501593D03*
Y1507593D03*
X1040583Y1517883D03*
X1031799Y1534392D03*
X1031882Y1528985D03*
X1026459Y1528919D03*
X1026376Y1534326D03*
X1014867D03*
X1014950Y1528919D03*
X1020290Y1534392D03*
X1020373Y1528985D03*
X1040500Y1529290D03*
X1040583Y1523883D03*
X1062700Y1463100D03*
X1058200D03*
X1067200D03*
X1062700Y1467600D03*
X1058200D03*
X1067200D03*
X1053700Y1463100D03*
Y1467600D03*
X1062700Y1472100D03*
X1058200D03*
X1067200D03*
Y1476600D03*
X1058200D03*
X1062700D03*
X1053700Y1472100D03*
Y1476600D03*
X1078683Y1489593D03*
X1051383D03*
X1041810Y1511084D03*
X1055310D03*
X1059810D03*
X1064310D03*
X1068810D03*
X1073310D03*
X1078683Y1495593D03*
Y1501593D03*
Y1507593D03*
Y1516593D03*
X1051383Y1495593D03*
Y1501593D03*
Y1507593D03*
X1078683Y1522593D03*
G54D14*
X19712Y1176350D03*
X25000Y1190400D03*
X64487Y201761D03*
X53087Y179561D03*
X49937Y219661D03*
X54437D03*
X58937D03*
X47607Y527511D03*
X61834Y527515D03*
X72500Y508600D03*
X67500D03*
X53087Y632317D03*
X58937Y672417D03*
X54437D03*
X49937D03*
X64487Y654417D03*
X27143Y663071D03*
X27510Y688422D03*
X58175Y981325D03*
X67500Y961355D03*
X72500D03*
X58937Y1125173D03*
X54437D03*
X49937D03*
X64487Y1107173D03*
X53027Y1085073D03*
X39325Y1131400D03*
X26723Y1116038D03*
X36848Y1173600D03*
X27090Y1141389D03*
X31500Y1224000D03*
X39425Y1226200D03*
X30000Y1190400D03*
X37225Y1230100D03*
X45518Y1336366D03*
X41381Y1335567D03*
X95437Y176661D03*
Y181161D03*
X73937Y201661D03*
X78937D03*
X83937D03*
X88937D03*
X85146Y621637D03*
X95437Y633917D03*
X88937Y654417D03*
X83937D03*
X78937D03*
X73937D03*
X101403Y981195D03*
X97063Y973225D03*
X98563Y977225D03*
X114100Y1002600D03*
X99700Y991400D03*
X108063Y991925D03*
X114300Y992362D03*
X104230Y992209D03*
X95537Y1082173D03*
Y1086673D03*
X73937Y1107173D03*
X78937D03*
X83937D03*
X88937D03*
X142687Y248100D03*
X145437Y265561D03*
X166400Y579400D03*
X168103Y569195D03*
X163763Y561225D03*
X165263Y565225D03*
X150253Y709713D03*
X145437Y717617D03*
X142687Y700767D03*
X140364Y749807D03*
X137163Y987125D03*
X130463Y983925D03*
X133063Y1012725D03*
X137063Y993725D03*
X145363Y997741D03*
X131110Y993257D03*
X148400Y1086900D03*
X145437Y1165673D03*
X150862Y1152723D03*
X142687Y1153523D03*
X148300Y1228800D03*
X148311Y1182767D03*
X135422Y1190937D03*
X140422D03*
X163500Y1345200D03*
X188699Y200561D03*
X177399Y179661D03*
X198149Y201661D03*
X203149D03*
X208149D03*
X213149D03*
X174149Y219661D03*
X178649D03*
X183149D03*
X171861Y527469D03*
X186088Y527473D03*
X196712Y508600D03*
X191712D03*
X210263Y546725D03*
X180800Y590600D03*
X207313Y598113D03*
X203763Y581725D03*
X212063Y585741D03*
X197810Y581257D03*
X174763Y579925D03*
X203863Y575125D03*
X181000Y580362D03*
X170930Y580209D03*
X197163Y571925D03*
X185149Y617949D03*
X199763Y600725D03*
X210000Y650000D03*
X182259Y672559D03*
X177759D03*
X173259D03*
X198149Y654417D03*
X203149D03*
X208149D03*
X213149D03*
X199900Y923200D03*
X216712Y961155D03*
X188399Y1102873D03*
X183149Y1125173D03*
X178649D03*
X174149D03*
X177105Y1094839D03*
X195100Y1096800D03*
X198149Y1107173D03*
X203149D03*
X208149D03*
X213149D03*
X219749Y176661D03*
Y181361D03*
X266899Y248011D03*
X219749Y618917D03*
Y623417D03*
X258600Y715500D03*
X266899Y700767D03*
X264731Y749551D03*
X223100Y920600D03*
X239000Y985600D03*
X221712Y961155D03*
X252100Y990100D03*
X244600Y1004600D03*
X261100Y1005700D03*
X227063Y994925D03*
X219749Y1082173D03*
X264864Y1120500D03*
X219749Y1086873D03*
X264594Y1190768D03*
X259594D03*
X312079Y68379D03*
X303029Y68429D03*
X313628Y112926D03*
X303000Y73500D03*
X314370Y118452D03*
X314439Y133669D03*
X312912Y201661D03*
X301612Y179661D03*
X298362Y219661D03*
X302862D03*
X307362D03*
X269649Y266261D03*
X291601Y418503D03*
X292153Y486059D03*
X306388Y486022D03*
X296032Y527469D03*
X310259Y527473D03*
X293763Y582925D03*
X301612Y632417D03*
X307362Y672417D03*
X302862D03*
X298362D03*
X312912Y654417D03*
X274520Y709457D03*
X268100Y982300D03*
X273300Y981700D03*
X280800Y1011900D03*
X281200Y1033000D03*
X271100Y1063200D03*
X281500Y1036744D03*
X307362Y1125173D03*
X302862D03*
X298362D03*
X313232Y1106499D03*
X301327Y1085173D03*
X269649Y1165673D03*
X275385Y1152596D03*
X271165Y1147172D03*
X315500Y1216700D03*
X276100Y1229100D03*
X273243Y1182915D03*
X286925Y1201945D03*
X295900Y1339700D03*
X296100Y1335100D03*
X279900Y1328300D03*
X283700D03*
X286100Y1349659D03*
X292600Y1337367D03*
X289510Y1342259D03*
X354100Y62100D03*
X322500Y68345D03*
X334845Y58745D03*
X361776Y70842D03*
X335081Y104081D03*
X339219Y95188D03*
X339914Y82415D03*
X344304Y82439D03*
X345321Y102400D03*
X347647Y95614D03*
X353001Y114815D03*
X347881Y114881D03*
X351416Y95788D03*
X337641Y114910D03*
X334947Y94605D03*
X342761Y114861D03*
X350441Y117541D03*
X337721Y129821D03*
X323813Y118512D03*
X341114Y123622D03*
X345321Y118921D03*
X323813Y133722D03*
X344062Y176461D03*
X343962Y181161D03*
X322362Y201661D03*
X327362D03*
X332362D03*
X337362D03*
X320474Y379474D03*
X316534D03*
X320474Y363234D03*
X316534D03*
X320925Y485385D03*
X315925D03*
X320925Y508600D03*
X315925D03*
X333682Y621858D03*
X343862Y633917D03*
X322362Y654417D03*
X327362D03*
X332362D03*
X337362D03*
X320474Y832229D03*
X316534D03*
X320925Y938140D03*
X315600Y933600D03*
X335300Y926900D03*
X337100Y972100D03*
X320925Y961355D03*
X315925D03*
X344737Y995637D03*
X350673Y1031200D03*
X344062Y1082073D03*
Y1086773D03*
X322362Y1107173D03*
X327362D03*
X332362D03*
X337362D03*
X331679Y1175800D03*
X377144Y84720D03*
X377944Y95929D03*
X390412Y248011D03*
X386800Y263800D03*
X393862Y719917D03*
X398677Y709385D03*
X391112Y700767D03*
X388788Y749479D03*
X407714Y761291D03*
X398254Y763517D03*
X408672Y1008038D03*
X388888Y1118173D03*
X393679Y1157480D03*
X383191Y1170203D03*
X391112Y1153500D03*
X398527Y1188659D03*
X383849Y1190833D03*
X388849Y1191148D03*
X398527Y1233336D03*
X437124Y201661D03*
X429224Y176300D03*
X446951Y213656D03*
X451951D03*
X456951D03*
X431574Y219661D03*
X427074D03*
X422574D03*
X441645Y288847D03*
Y284647D03*
X456190Y354105D03*
X444687Y379474D03*
X440747D03*
X444687Y363234D03*
X440747D03*
X452800Y420912D03*
X418600Y445462D03*
X421700Y450200D03*
X445138Y487743D03*
X440138D03*
X447533Y475900D03*
X458679Y470700D03*
X450500Y459562D03*
X416303Y486022D03*
X430538Y485985D03*
X420182Y527432D03*
X434409Y527436D03*
X440138Y508600D03*
X445138D03*
X425824Y632317D03*
X457853Y622091D03*
X437224Y654417D03*
X431574Y672417D03*
X427074D03*
X422574D03*
X456574Y654417D03*
X451574D03*
X446574D03*
X444687Y832229D03*
X440747D03*
X444687Y816765D03*
X440747D03*
X445138Y938140D03*
X440138D03*
X435082Y915200D03*
X437600Y917800D03*
X445582Y925352D03*
X449137Y967757D03*
X440138Y961355D03*
X445138D03*
X429613Y1017920D03*
X432657Y1015102D03*
X442600Y998300D03*
X413000Y1054200D03*
X442473Y1068726D03*
X447173D03*
X456919Y1121725D03*
X447919D03*
X452419D03*
X441976Y1107576D03*
X446627Y1112973D03*
X441400Y1169400D03*
X416900Y1221800D03*
X412300Y1326200D03*
X415422Y1352000D03*
X422373Y1359747D03*
X418922Y1356522D03*
X462200Y173109D03*
X468472Y182441D03*
X461951Y213656D03*
X462133Y473300D03*
X481533Y480875D03*
X497351Y531531D03*
X501023Y534941D03*
X472022Y582062D03*
X468174Y633917D03*
X461574Y654417D03*
X465200Y1018200D03*
X506500Y1051900D03*
X504724Y1107073D03*
X505874Y1134773D03*
X506700Y1145973D03*
X508103Y1190557D03*
X509180Y145419D03*
X546009Y187821D03*
X539584Y184694D03*
X542155Y187543D03*
X557057Y220152D03*
X553674Y220121D03*
X550219Y220111D03*
X515324Y252511D03*
X553742Y267705D03*
X510700Y277200D03*
X534905Y354105D03*
X539350Y487659D03*
X534350D03*
X510621Y486059D03*
X524856Y486022D03*
X518700Y548700D03*
X553279Y523331D03*
X514500Y524469D03*
X528727Y524973D03*
X553279Y513331D03*
X530130Y547167D03*
X534350Y508600D03*
X539350D03*
X557279Y570331D03*
X527179Y568731D03*
X549937Y632317D03*
X555787Y672417D03*
X551287D03*
X546787D03*
X509996Y716996D03*
X522773Y709638D03*
X515324Y700667D03*
X512884Y749732D03*
X530800Y1028300D03*
X515800Y1028000D03*
X556022Y1042817D03*
X552436Y1042494D03*
X546787Y1125173D03*
X551287D03*
X555787D03*
X549773Y1085173D03*
X514474Y1107073D03*
X519474D03*
X524474D03*
X529474D03*
X509037Y1136700D03*
X524828Y1159231D03*
X522867Y1190284D03*
X513103Y1190557D03*
X522867Y1231097D03*
X520600Y1324100D03*
X536000Y1359826D03*
X541362D03*
X518397Y1360000D03*
X512900Y1345600D03*
X553587Y1346026D03*
X527000Y1340600D03*
X521500Y1342800D03*
X566271Y167387D03*
X561437Y197249D03*
X592767Y179277D03*
X598236Y181981D03*
X582697Y200744D03*
X577697D03*
X572697D03*
X587697D03*
X568899Y379474D03*
X564959D03*
X568899Y363234D03*
X564959D03*
X602379Y547831D03*
X570779Y542831D03*
X568779Y512831D03*
X575779D03*
X593079Y516531D03*
Y512531D03*
X585479Y537731D03*
Y543994D03*
X572229Y520081D03*
X580279Y512831D03*
X571408Y577450D03*
X584279Y577431D03*
X575779D03*
X579718D03*
X592779D03*
X588779D03*
X562279D03*
X567641Y577473D03*
X571529Y562951D03*
X579529D03*
X602779Y552331D03*
X592387Y629417D03*
Y634017D03*
X561437Y654417D03*
X585787D03*
X580787D03*
X575787D03*
X570787D03*
X568899Y832229D03*
X564959D03*
X593365Y877358D03*
X592614Y882300D03*
X569350Y941640D03*
X564350D03*
X569350Y961355D03*
X564350D03*
X571400Y1000100D03*
X592387Y1082173D03*
X561337Y1107173D03*
X592387Y1086873D03*
X570787Y1107173D03*
X575787D03*
X580787D03*
X585787D03*
X600640Y1171000D03*
X592400Y1214456D03*
X607929Y112329D03*
X619171D03*
X639537Y248011D03*
X642287Y266461D03*
X652663Y502400D03*
X647663D03*
X612000Y502300D03*
X624028Y503558D03*
X638263Y503494D03*
X615119Y551586D03*
X627000Y538581D03*
Y542909D03*
X609334Y538306D03*
Y543306D03*
X619560Y547201D03*
X627863Y522000D03*
X642509Y520667D03*
X652663Y516600D03*
X647663D03*
X615147Y565956D03*
X637213Y582155D03*
X623236Y562574D03*
X642287Y719817D03*
X647207Y709555D03*
X639537Y700767D03*
X637318Y749649D03*
X645200Y1067800D03*
X636803Y1167864D03*
X642942Y1156818D03*
X632603Y1136225D03*
X647716Y1154150D03*
X639537Y1153523D03*
X627632Y1217300D03*
X647126Y1189513D03*
X632316Y1190474D03*
X637316D03*
X687566Y109568D03*
X663449Y115606D03*
X690807Y103298D03*
X677450Y185669D03*
X685250Y199493D03*
X699950Y200846D03*
X694950D03*
X674313Y220374D03*
X669813D03*
X689232Y355251D03*
X693112Y385976D03*
X689172D03*
Y358978D03*
X658646Y515180D03*
X658681Y571798D03*
X654681D03*
X683341Y580479D03*
X689747D03*
X682000Y628449D03*
X685550Y654417D03*
X679929Y673058D03*
X675429D03*
X670929D03*
X700000Y654417D03*
X695000D03*
X658574Y930100D03*
X677457Y944796D03*
X688563Y961355D03*
X693563D03*
X663800Y1018300D03*
X682200Y1026500D03*
X674300Y1001620D03*
X685250Y1102873D03*
X680000Y1125173D03*
X675500D03*
X671000D03*
X674700Y1098500D03*
X695000Y1107173D03*
X700000D03*
X664000Y1278100D03*
X673000Y1354100D03*
X747242Y197553D03*
X717188Y176461D03*
X716600Y181161D03*
X709950Y200846D03*
X704950D03*
X705348Y478425D03*
X716600Y629417D03*
Y633917D03*
X710000Y654417D03*
X705000D03*
X724283Y860689D03*
X737984Y861689D03*
X741883Y861389D03*
X733883Y935689D03*
X736883Y938689D03*
Y929189D03*
Y933689D03*
X747383Y924689D03*
X733883Y940689D03*
X736462Y948996D03*
X736883Y943189D03*
X716600Y1081973D03*
Y1086673D03*
X705000Y1107173D03*
X710000D03*
X728174Y1275611D03*
X725678Y1272799D03*
X722790Y1270557D03*
X720446Y1267427D03*
X731500Y1277811D03*
X757020Y159692D03*
X758619Y168537D03*
X767405Y210364D03*
X763188Y172500D03*
X789739Y365493D03*
X754500Y668741D03*
X755000Y677700D03*
X765124Y864089D03*
X766707Y872260D03*
X762453Y872413D03*
X765025Y867802D03*
X757664Y868974D03*
X753893Y912630D03*
X776400Y956500D03*
X780800Y959300D03*
X786800Y1016000D03*
X784000Y1024000D03*
X759500Y1056100D03*
X779535Y1180469D03*
X792263Y1178661D03*
Y1174461D03*
Y1170261D03*
X752500Y1167500D03*
X756250Y1151750D03*
X784544Y1210178D03*
Y1205978D03*
X779535Y1193469D03*
Y1189269D03*
Y1184669D03*
X797177Y1189537D03*
X797225Y1185337D03*
X792263Y1182861D03*
X792336Y1319537D03*
X782230Y1323670D03*
X769728Y1325747D03*
X785340Y1320410D03*
X789549Y1322310D03*
X777009Y1322690D03*
X781290Y1328490D03*
X772900Y1328550D03*
X790290Y1328410D03*
X785640Y1328370D03*
X796848Y1469724D03*
X829921Y-458D03*
X825984D03*
X833724Y-3346D03*
X833671Y254D03*
X806299Y-458D03*
X802362D03*
X814173D03*
X810236D03*
X822047D03*
X818110D03*
X845661Y-3642D03*
X843463Y530D03*
X806314Y35952D03*
X802350Y35923D03*
X842470Y41295D03*
X841733Y36654D03*
X818300Y39845D03*
X814300D03*
Y43845D03*
X818300D03*
X810301Y78654D03*
X805301D03*
X802801Y75654D03*
X807801D03*
X812801D03*
X846400Y473900D03*
X839500Y508500D03*
X809015Y661000D03*
X804015D03*
X808920Y652340D03*
Y656460D03*
X806515Y664000D03*
X802036Y1164244D03*
X803438Y1139700D03*
X809600Y1236300D03*
X804600D03*
X802100Y1233300D03*
X807100D03*
X812100D03*
X806952Y1460496D03*
X806568Y1464275D03*
X802433Y1461619D03*
X800900Y1465234D03*
X800462Y1469231D03*
X834813Y1528889D03*
X834974Y1533243D03*
X886322Y69D03*
X867080Y393D03*
X886427Y3802D03*
X873892Y287D03*
X886418Y-7350D03*
X849484Y649D03*
X886351Y-3735D03*
X857513Y659D03*
X885448Y37380D03*
X877265Y52540D03*
X881265D03*
X885265D03*
X873265D03*
X869265D03*
X869459Y56626D03*
Y61626D03*
X869044Y66985D03*
X873044D03*
X877139Y66926D03*
X885265Y60540D03*
Y56540D03*
X881750Y37397D03*
X858496Y37121D03*
X854180Y36996D03*
X852995Y40965D03*
X856995D03*
X886073Y78824D03*
X885464Y83201D03*
X878549Y78905D03*
Y82905D03*
X869044Y70985D03*
X873044D03*
X882549Y76905D03*
Y80905D03*
X872796Y251714D03*
X881549Y326304D03*
X890982Y349498D03*
X874800Y355798D03*
X887100Y359100D03*
X887500Y378495D03*
X875132Y399200D03*
X878732D03*
Y395600D03*
X875132D03*
X878732Y392000D03*
X875132D03*
X880932Y406400D03*
Y402800D03*
X877332Y406400D03*
Y402800D03*
X874807Y375193D03*
X866276Y454900D03*
X866317Y446725D03*
X880932Y410000D03*
X877332D03*
X857300Y454300D03*
X862000Y453600D03*
X852000Y454200D03*
X866321Y451300D03*
X878500Y476000D03*
X878193Y467707D03*
X866278Y459562D03*
X870600Y476900D03*
X851800Y477200D03*
X874715Y707651D03*
X871115D03*
X867515D03*
X884700Y705200D03*
X881100D03*
X877500D03*
X887600Y811900D03*
X891200Y838200D03*
X878673Y804527D03*
X874569Y811300D03*
X885882Y861618D03*
X894965Y843500D03*
X877673Y868873D03*
X888962Y843262D03*
X873647Y861653D03*
X882333Y896320D03*
X895616Y985932D03*
X863800Y1309876D03*
X872164Y1350464D03*
X873259Y1365805D03*
X872181Y1354764D03*
X886792Y1404100D03*
X873918Y1411149D03*
X873800Y1418200D03*
X871432Y1420932D03*
X874900Y1421900D03*
X877406Y1419124D03*
X875740Y1415070D03*
X882226Y1404197D03*
X873694Y1404575D03*
X873700Y1375746D03*
X873570Y1380401D03*
X872192Y1424492D03*
X882000Y1432600D03*
X870921Y1432300D03*
X888800Y1493500D03*
X876514Y1514948D03*
X863851Y1501681D03*
X877828Y1500379D03*
X892966Y1508549D03*
X893036Y1512600D03*
X877946Y1496527D03*
X876096Y1505499D03*
X889002Y1489638D03*
X873972Y1472467D03*
X873922Y1477766D03*
X860179Y1491170D03*
X893020Y1566530D03*
X876200Y1553900D03*
X892700Y1543900D03*
X892558Y1528458D03*
X889300Y1551000D03*
X876190Y1537187D03*
X876100Y1549000D03*
X876200Y1558400D03*
X892700Y1524700D03*
X848551Y1542440D03*
X922687Y93D03*
X928138Y-8453D03*
X942000Y752850D03*
X897000Y839000D03*
X903000Y842500D03*
X920810Y902210D03*
X928100Y900650D03*
X900615Y909723D03*
X902571Y906534D03*
X903368Y934568D03*
X904594Y931141D03*
X916204Y938572D03*
X917550Y934742D03*
X901540Y937712D03*
X896679Y927505D03*
X896420Y916712D03*
X898468Y912970D03*
X931085Y936172D03*
X941274Y900845D03*
X934142Y974344D03*
X939481Y980230D03*
X912994Y971921D03*
X910397Y979189D03*
X902991Y982230D03*
X909826Y982874D03*
X905271Y974586D03*
X899846Y971468D03*
X898617Y975434D03*
X895837Y978389D03*
X896629Y982285D03*
X935623Y971054D03*
X904601Y998556D03*
X910040Y1006613D03*
X911807Y1002342D03*
X919656Y998764D03*
X939544Y1003485D03*
X903442Y1003265D03*
X896371Y1002112D03*
X936378Y1035722D03*
X920770Y1067389D03*
X921149Y1062424D03*
X914948Y1063255D03*
X908477Y1061823D03*
X910387Y1055344D03*
X904875Y1051177D03*
X896500Y1341800D03*
X936959Y1360143D03*
X896212Y1345788D03*
X895900Y1390100D03*
X896200Y1386000D03*
X896100Y1393800D03*
X896200Y1397900D03*
Y1405300D03*
X896100Y1401600D03*
X923829Y1389012D03*
X936994Y1379895D03*
X927601Y1384433D03*
X923486Y1384268D03*
X906600Y1461600D03*
X909400Y1459200D03*
X910000Y1464900D03*
X905500Y1467161D03*
X938000Y1499200D03*
X942000Y1499500D03*
X922500Y1499700D03*
X908742Y1477427D03*
X908542Y1481127D03*
X922500Y1509700D03*
X941000Y1564200D03*
X937000D03*
X926500Y1556700D03*
X931500Y1564200D03*
X913250Y1547700D03*
X940000Y1529200D03*
X940750Y1549200D03*
X900000Y1526500D03*
X897400Y1574000D03*
X897038Y1577600D03*
X911516Y1573202D03*
X911616Y1576802D03*
X911710Y1582375D03*
X911094Y1585923D03*
X924059Y1647700D03*
X981700Y-115500D03*
X976713Y-115570D03*
X991713Y-115413D03*
X989316Y-94984D03*
X992185Y-54411D03*
X989050Y-70850D03*
X990565Y130230D03*
Y135230D03*
Y125230D03*
X985688Y362549D03*
X977794Y695103D03*
X952200Y742600D03*
X957100Y742900D03*
X977622Y699464D03*
X953200Y736700D03*
X956900Y737600D03*
X949048Y755225D03*
X952476Y753652D03*
X951300Y747900D03*
X956200Y748200D03*
X957320Y769818D03*
X947866Y763541D03*
X957629Y766231D03*
X952820Y769518D03*
X944500Y760750D03*
X961100Y931640D03*
X960503Y936185D03*
X967583Y933607D03*
X968698Y928957D03*
X974484Y935078D03*
X976419Y931628D03*
X976460Y927891D03*
X981679Y936678D03*
X976213Y938846D03*
X966000Y937500D03*
X953013Y960147D03*
X947174Y957150D03*
X979020Y960000D03*
Y956200D03*
X973900Y960000D03*
Y956200D03*
X968780Y960000D03*
Y956200D03*
X987734Y979575D03*
X951200Y1030700D03*
X946700D03*
X947759Y998726D03*
X961220Y1001600D03*
Y1005400D03*
X966340Y1001600D03*
Y1005400D03*
X971460Y1001600D03*
Y1005400D03*
X974020Y1026200D03*
Y1022400D03*
X968900Y1026200D03*
Y1022400D03*
X963780Y1026200D03*
Y1022400D03*
X956600Y1001700D03*
Y1005700D03*
X964537Y1160310D03*
X958870Y1163617D03*
X962941Y1165929D03*
X967497Y1168802D03*
X957871Y1171219D03*
X963000Y1174427D03*
X969463Y1177599D03*
X972924Y1158033D03*
X954395Y1145604D03*
X982387Y1183598D03*
X951525Y1369107D03*
X955500Y1369000D03*
X946300Y1499300D03*
X969198Y1505851D03*
X969472Y1501978D03*
X950300Y1499500D03*
X975813Y1556916D03*
X953500Y1563200D03*
X962000Y1564200D03*
X958000D03*
X949000D03*
X945000D03*
X972001Y1533926D03*
X975813Y1545916D03*
X954700Y1524100D03*
Y1530363D03*
X974787Y1525100D03*
Y1529300D03*
X948750Y1549200D03*
X979963Y1545689D03*
X1004213Y-95837D03*
X998045Y-79300D03*
X993816Y-95184D03*
X1036713Y-115500D03*
X1007582Y-39418D03*
X1000300Y-74200D03*
X1032080Y-45980D03*
X1004082Y-38200D03*
X1000418Y-69982D03*
X993000Y-60600D03*
X1019118Y-34382D03*
X1019082Y-71000D03*
X1026717Y-11646D03*
X1021086Y-11682D03*
X1010650Y49950D03*
Y67650D03*
X1030775Y130016D03*
X1030890Y137780D03*
X993565Y137730D03*
Y132730D03*
Y127730D03*
X1030774Y133840D03*
X1030758Y126274D03*
X1030825Y122335D03*
X1020250Y357188D03*
X1040180Y437510D03*
X1038215Y877191D03*
X1034271Y876911D03*
X1011100Y904600D03*
X1025000Y897700D03*
X1036431Y929752D03*
X1037083Y933300D03*
X1016842Y916445D03*
X1035947Y948800D03*
X1028657Y1009103D03*
X1020654Y1023940D03*
X1018094Y1021240D03*
X1015534Y1023840D03*
X1007849Y1033743D03*
X996600D03*
X1012974Y1021240D03*
X1013700Y1007640D03*
X1009509Y1009850D03*
X1037282Y995028D03*
X1005294Y997940D03*
Y1001740D03*
X1010414Y997940D03*
Y1001740D03*
X1023214Y1007140D03*
X1007372Y1023832D03*
X1017194Y1033840D03*
X1026900Y1129466D03*
X1022400Y1129183D03*
X1036160Y1095500D03*
Y1091700D03*
Y1111900D03*
X994923Y1137488D03*
X995948Y1184250D03*
X1017354Y1196124D03*
X1021061Y1198543D03*
X1016835Y1323916D03*
X1025335Y1324216D03*
X1016672Y1338228D03*
X1025284Y1341216D03*
X1025335Y1337616D03*
Y1330916D03*
X1016600Y1332000D03*
X1033000Y1416125D03*
X1028000Y1404700D03*
Y1411000D03*
X1031500Y1408000D03*
X1020854Y1455075D03*
X1016854D03*
X1051713Y-114887D03*
X1056713Y-115413D03*
X1086713Y-115570D03*
X1081713D03*
X1071713D03*
X1066713D03*
X1041713Y-115465D03*
X1085300Y-90700D03*
X1079455Y-30742D03*
X1043000Y-67600D03*
X1043112Y-34912D03*
X1066600Y-72800D03*
X1066225Y-40278D03*
X1054593Y-51122D03*
X1078900Y-45782D03*
X1085800Y-57100D03*
X1070918Y-73618D03*
X1043303Y-27685D03*
X1045873Y-24660D03*
X1043513Y-21696D03*
X1077505Y22405D03*
X1076418Y31082D03*
X1076944Y35182D03*
X1077260Y42612D03*
X1077400Y52000D03*
X1077082Y38982D03*
X1076905Y46195D03*
X1076299Y27282D03*
X1054800Y22405D03*
X1041500Y382858D03*
X1078100Y392600D03*
Y397600D03*
Y402600D03*
X1072600Y392500D03*
Y397500D03*
Y402500D03*
X1045292Y384688D03*
X1074425Y447225D03*
X1071950Y453288D03*
X1072600Y407500D03*
X1078100Y407600D03*
X1043674Y451921D03*
X1043500Y446600D03*
X1042800Y442000D03*
X1069018Y456900D03*
X1065985Y460500D03*
X1054419Y839493D03*
Y828081D03*
X1050763Y829163D03*
X1086600Y833200D03*
X1044101Y927130D03*
X1083633Y932172D03*
X1073408Y942399D03*
X1058571Y943852D03*
X1053099Y1021657D03*
X1048512Y1021378D03*
X1041616Y997225D03*
X1069000Y1067100D03*
X1083355Y1125903D03*
X1070155D03*
X1048960Y1113900D03*
Y1117700D03*
X1041280Y1121500D03*
Y1113900D03*
Y1117700D03*
X1081078Y1095362D03*
X1083660Y1092700D03*
X1041280Y1095500D03*
Y1091700D03*
Y1100500D03*
X1048960Y1095500D03*
Y1091700D03*
Y1099300D03*
X1054080Y1113900D03*
Y1117700D03*
X1068700Y1108700D03*
X1083355Y1116103D03*
X1070155D03*
X1075600Y1179090D03*
X1053743Y1174221D03*
X1046900Y1168000D03*
X1052522Y1145153D03*
X1076032Y1191144D03*
X1070000Y1184100D03*
X1079500Y1276100D03*
X1047000Y1258687D03*
X1051300Y1253300D03*
X1077300Y1271700D03*
X1042343Y1324216D03*
X1048251Y1349992D03*
X1046372Y1356326D03*
X1042343Y1337616D03*
X1042443Y1342668D03*
X1042343Y1330916D03*
X1076754Y1455075D03*
X1072754D03*
X1044654D03*
X1048654D03*
X1100929Y-90371D03*
X1116600Y-85538D03*
X1106300Y-94800D03*
X1089318Y-91682D03*
X1101246Y-31005D03*
X1124024Y-30840D03*
X1128765Y-34297D03*
X1094200Y-38400D03*
X1111254Y-31020D03*
X1105328Y-31005D03*
X1094300Y-60300D03*
X1103300Y-60000D03*
X1115603Y-60293D03*
X1134110Y176500D03*
X1136203Y167600D03*
X1089300Y836100D03*
X1119419Y888607D03*
X1116419Y896107D03*
Y891107D03*
X1119419Y893607D03*
Y898607D03*
X1110447Y944217D03*
X1105447D03*
X1100447D03*
X1102947Y947217D03*
X1107947D03*
X1091400Y1070900D03*
X1091494Y1075994D03*
X1097800Y1070700D03*
X1097500Y1075100D03*
X1103800Y1070600D03*
Y1075600D03*
X1128900Y1067200D03*
X1119500Y1125100D03*
X1115000D03*
X1123600Y1096400D03*
X1123838Y1092800D03*
X1123600Y1100000D03*
X1133981Y1096283D03*
X1134002Y1092600D03*
X1134103Y1099881D03*
X1137436Y1124750D03*
X1128800Y1125100D03*
X1092200Y1125800D03*
X1103064Y1113626D03*
X1099020Y1112276D03*
X1096460Y1115125D03*
X1092742Y1113462D03*
X1134100Y1433300D03*
X1146768Y-31238D03*
X1139808Y-31171D03*
X1149699Y-35153D03*
X1142293Y-37522D03*
X1181568Y55168D03*
X1181868Y50568D03*
Y45568D03*
X1181568Y60168D03*
X1178268Y64068D03*
X1183268D03*
X1178268Y85068D03*
Y69068D03*
Y89068D03*
X1183268Y85068D03*
Y69068D03*
Y89068D03*
X1178656Y104637D03*
X1176952Y93390D03*
X1140550Y179200D03*
X1142800Y174637D03*
X1140500Y171400D03*
X1171749Y259163D03*
X1175400Y258800D03*
X1176300Y284500D03*
X1180953Y284800D03*
X1185588Y285035D03*
X1185000Y281343D03*
X1176100Y270603D03*
X1176300Y288600D03*
X1169768Y730300D03*
Y723100D03*
Y726700D03*
X1175568Y712300D03*
X1171968D03*
X1175568Y715900D03*
X1171968D03*
X1173368Y730300D03*
X1171968Y719500D03*
X1175568D03*
X1173368Y726700D03*
Y723100D03*
X1138198Y832424D03*
X1172736Y1031786D03*
X1177036Y1032086D03*
X1170140Y1043939D03*
X1152880Y1097672D03*
X1152682Y1091138D03*
X1149984Y1115804D03*
X1143550Y1120317D03*
X1139524Y1121817D03*
X1152800Y1223062D03*
X1152700Y1216213D03*
X1150420Y1229800D03*
X1181400Y1266100D03*
X1184000Y1260100D03*
X1149823Y1233373D03*
X1144000Y1310000D03*
X1150232Y1316358D03*
X1154500Y1327500D03*
X1150911Y1329500D03*
X1147900Y1421500D03*
X1143900Y1431000D03*
X1142400Y1427700D03*
X1146002Y1427906D03*
X1145007Y1424446D03*
X1148556Y1425056D03*
X1188268Y64068D03*
Y85068D03*
Y69068D03*
Y89068D03*
X1215795Y181242D03*
X1215600Y261800D03*
X1219962Y244739D03*
X1186600Y253200D03*
X1215547Y246355D03*
X1194700Y261700D03*
X1189700Y308527D03*
X1190200Y285023D03*
X1201835Y305319D03*
X1193800Y307857D03*
X1198100Y306858D03*
X1194600Y288237D03*
X1197000Y279400D03*
X1226045Y431102D03*
X1194000Y1037900D03*
X1232842Y1140722D03*
X1198130Y1151410D03*
X1205303Y1227604D03*
X1250016Y247017D03*
X1253300Y227700D03*
X1262075Y297100D03*
X1250500Y266600D03*
X1239362Y524168D03*
X1253511Y517606D03*
X1264878Y508068D03*
X1268400Y716100D03*
X1265891Y699583D03*
X1263250Y823436D03*
X1243200Y933700D03*
X1259808Y927260D03*
X1271296Y986867D03*
X1274413Y984613D03*
X1279599Y976407D03*
X1253338Y980784D03*
X1253975Y970147D03*
X1264269Y981248D03*
X1263618Y990606D03*
X1268378Y990608D03*
X1239900Y1024000D03*
X1256142Y1029316D03*
X1252400Y1054100D03*
X1272755Y1137293D03*
X1260300Y1169000D03*
X1240314Y1139741D03*
X1268948Y1150173D03*
X1254800Y1269600D03*
X1240276Y1356700D03*
X1323829Y55929D03*
X1328295Y55800D03*
X1320055Y68000D03*
X1304563Y100771D03*
X1299569Y100639D03*
X1312263Y95463D03*
X1327921Y78900D03*
X1308228Y93399D03*
X1315961Y98112D03*
X1314794Y162944D03*
X1324134Y126967D03*
X1313127Y120839D03*
X1315118Y126967D03*
X1324207Y138756D03*
X1315102Y137903D03*
X1330807Y181473D03*
X1311750Y187911D03*
X1326637Y226568D03*
X1316637D03*
X1321637D03*
X1326500Y627917D03*
X1311750Y640667D03*
X1312000Y615417D03*
X1318000Y680417D03*
X1323000D03*
X1328000D03*
X1316000Y772200D03*
X1310500Y774700D03*
X1312767Y885535D03*
X1286000Y982200D03*
X1284695Y956586D03*
X1326500Y1080673D03*
X1317400Y1068000D03*
X1309600Y1068173D03*
X1311750Y1093423D03*
X1328000Y1133173D03*
X1318000D03*
X1323000D03*
X1351200Y68600D03*
X1359350Y66350D03*
X1358355Y81488D03*
X1338215Y107586D03*
X1336034Y82542D03*
X1334383Y75892D03*
X1340961Y78811D03*
X1343521Y85472D03*
X1347607Y101337D03*
X1346081Y80671D03*
X1348641Y83326D03*
X1352351Y101724D03*
X1350779Y106496D03*
X1348641Y110550D03*
X1333281Y85133D03*
X1341922Y105649D03*
X1354500Y75400D03*
X1349931Y138361D03*
X1338400Y126015D03*
X1333988Y161471D03*
X1358971Y129978D03*
X1362685Y130109D03*
X1351665Y128325D03*
X1343112Y128997D03*
X1364017Y123277D03*
X1337662Y137188D03*
X1334500Y202548D03*
Y207548D03*
Y212548D03*
Y217548D03*
X1372274Y272874D03*
X1355991Y275272D03*
X1374338Y292900D03*
X1358573Y290900D03*
X1375700Y413400D03*
X1357316Y542311D03*
X1346057Y529857D03*
X1338100Y520300D03*
X1353500Y518900D03*
X1359882Y508014D03*
X1364882D03*
X1336000Y627000D03*
X1334000Y666417D03*
Y661917D03*
Y657417D03*
Y652917D03*
X1373553Y700994D03*
X1347600Y734078D03*
X1344062Y737800D03*
X1354500Y747304D03*
X1360920Y749829D03*
X1334300Y771200D03*
X1338729Y776131D03*
X1338700Y771500D03*
X1334329Y775831D03*
X1373519Y761900D03*
X1341219Y933282D03*
X1346080Y907004D03*
X1378100Y972100D03*
X1339404Y969600D03*
X1353762Y969886D03*
X1367382Y961355D03*
X1362382D03*
X1349829Y1014840D03*
X1365551Y1028250D03*
X1361074Y1114565D03*
X1334500Y1104700D03*
Y1111173D03*
Y1116173D03*
Y1121173D03*
X1360238Y1143867D03*
X1370716Y1148037D03*
X1351321Y1152553D03*
X1355733Y1241900D03*
X1369600Y1330100D03*
X1373700Y1330000D03*
X1365551Y1353500D03*
X1427663Y167032D03*
X1384475Y255839D03*
X1384713Y323200D03*
X1414882Y397271D03*
X1395300Y438500D03*
X1418225Y421700D03*
X1418493Y531407D03*
X1425600Y544600D03*
X1418507Y517007D03*
X1407936Y552099D03*
Y548099D03*
X1425200Y540100D03*
X1414319Y523900D03*
X1396297Y573397D03*
X1421239Y558029D03*
X1396297Y579803D03*
X1421239Y562229D03*
X1383952Y717435D03*
X1392355Y886696D03*
X1391000Y932400D03*
X1380300Y930200D03*
X1384800Y1002666D03*
X1383899Y1166690D03*
X1388500Y1224900D03*
X1381800Y1329600D03*
X1463804Y138605D03*
X1436204Y159247D03*
X1435963Y183833D03*
X1450713Y173049D03*
X1456373Y168971D03*
X1458764Y212625D03*
Y208025D03*
Y203425D03*
X1442213Y227661D03*
X1447213D03*
X1452213D03*
X1458764Y217225D03*
X1444238Y349852D03*
X1439654D03*
X1431909Y359311D03*
X1463000Y490638D03*
X1457200Y549600D03*
X1470700Y522100D03*
X1456439Y515000D03*
X1448261D03*
X1435200D03*
X1443700D03*
X1460200D03*
X1452200D03*
X1465700D03*
X1439200D03*
X1442500Y548400D03*
X1456450Y529600D03*
X1448450D03*
X1459200Y579600D03*
X1452200D03*
X1442500Y554700D03*
X1455750Y572350D03*
X1474700Y569100D03*
X1447700Y579600D03*
X1474700Y579100D03*
X1450713Y627817D03*
X1435963Y640667D03*
X1455202Y618557D03*
X1436213Y615417D03*
X1442213Y680417D03*
X1447213D03*
X1452213D03*
X1458713Y658417D03*
Y663417D03*
Y668417D03*
Y652217D03*
X1474083Y764750D03*
X1471608Y768500D03*
X1435300Y882700D03*
X1440500Y893500D03*
X1448000Y910000D03*
X1463616Y969265D03*
X1451800Y1004700D03*
X1450713Y1080673D03*
X1446213Y1062300D03*
X1436213Y1068173D03*
X1442213Y1132173D03*
X1447213D03*
X1452213D03*
X1439750Y1096673D03*
X1461713Y1123173D03*
Y1118173D03*
Y1113173D03*
X1461700Y1107200D03*
X1470953Y1152427D03*
X1475953D03*
X1467000Y1221800D03*
X1473600Y1242777D03*
X1511177Y125412D03*
X1499775Y248061D03*
X1508925Y323200D03*
X1481938Y489926D03*
X1485932Y522335D03*
X1500600Y523300D03*
X1502400Y544100D03*
X1497849Y545264D03*
X1486594Y508098D03*
X1491594D03*
X1513200Y519700D03*
X1509800Y516100D03*
X1494400Y560400D03*
Y556100D03*
X1500539Y739639D03*
X1498000Y743000D03*
X1505900Y717600D03*
X1495480Y704558D03*
X1489000Y723000D03*
X1476558Y759088D03*
X1479033Y762259D03*
X1486600Y786559D03*
X1505900Y930400D03*
X1521200Y928000D03*
X1503394Y968179D03*
X1477974Y970044D03*
X1491594Y961355D03*
X1486594D03*
X1484000Y992315D03*
X1481500Y995758D03*
X1478194Y1017166D03*
X1481529Y1030500D03*
X1485608Y1113628D03*
X1504200Y1171300D03*
X1485833Y1140369D03*
X1495900Y1149000D03*
X1491662Y1351300D03*
X1494662Y1336000D03*
X1497200Y1342500D03*
X1501600Y1342300D03*
X1560425Y162661D03*
X1560175Y187911D03*
X1566425Y227661D03*
X1571425D03*
X1568500Y438500D03*
Y544100D03*
X1568000Y548500D03*
X1555175Y642667D03*
X1560425Y615417D03*
X1566425Y677417D03*
X1571425D03*
X1565593Y654856D03*
X1565618Y660773D03*
Y665773D03*
Y670773D03*
X1526000Y728000D03*
X1570500Y888400D03*
X1570425Y1062000D03*
X1560425Y1068173D03*
X1547800Y1098819D03*
X1552800D03*
X1557800D03*
X1562800D03*
X1556231Y1134920D03*
X1558650Y1217426D03*
X1574925Y175061D03*
X1579371Y166019D03*
X1582925Y210661D03*
Y205661D03*
Y200661D03*
X1576425Y227661D03*
X1621100Y244661D03*
X1582925Y215661D03*
X1586596Y518723D03*
X1600745Y517561D03*
X1615807Y508600D03*
X1610807D03*
X1574925Y627817D03*
X1578926Y618657D03*
X1576425Y677417D03*
X1620469Y697517D03*
X1584800Y895800D03*
X1587400Y912200D03*
X1608200Y914400D03*
X1618200Y916800D03*
X1574576Y976700D03*
X1615494Y973179D03*
X1587829Y969191D03*
X1602187Y969970D03*
X1615807Y961355D03*
X1610807D03*
X1580381Y1007066D03*
X1602400Y1019366D03*
X1620059Y1032932D03*
X1574925Y1080673D03*
X1603425Y1105040D03*
Y1100040D03*
X1598425Y1102440D03*
Y1107440D03*
X1620059Y1128071D03*
X1615909Y1150262D03*
X1613400Y1236500D03*
X1622738Y264938D03*
X1621138Y719238D03*
X1643344Y887455D03*
X1646013Y884255D03*
X1639644Y889755D03*
X1633600Y936300D03*
X1621787Y917108D03*
X1636400Y925800D03*
X1629094Y975179D03*
X1624198Y1111309D03*
X1633138Y1165673D03*
X1635688Y1153773D03*
X1624500Y1349100D03*
X1684638Y162661D03*
X1684388Y187911D03*
X1699138Y175061D03*
X1703584Y166019D03*
X1707138Y210661D03*
Y205661D03*
Y200661D03*
X1690638Y227661D03*
X1695638D03*
X1700638D03*
X1707138Y215661D03*
X1711061Y518470D03*
X1684388Y638324D03*
X1699138Y627917D03*
X1705000Y618667D03*
X1684638Y615417D03*
X1699638Y675417D03*
X1689638D03*
X1694638D03*
X1707100Y652500D03*
X1707138Y658417D03*
Y663417D03*
Y668417D03*
X1692100Y923600D03*
X1704010Y898000D03*
X1674814Y961977D03*
X1677056Y954636D03*
X1680012Y952402D03*
X1685047Y1014966D03*
X1680087Y1023983D03*
X1671422Y1009266D03*
X1690279Y1011526D03*
X1691771Y1035163D03*
X1699138Y1080573D03*
X1685100Y1054000D03*
X1679300Y1043169D03*
X1694638Y1063600D03*
X1684638Y1068173D03*
X1700638Y1131673D03*
X1695638D03*
X1690638D03*
X1684388Y1091723D03*
X1707138Y1111173D03*
Y1116173D03*
Y1121173D03*
X1707200Y1105200D03*
X1702838Y1215300D03*
X1710617Y1231429D03*
X1715049Y1234000D03*
X1746400Y244561D03*
X1747550Y265000D03*
X1725100Y519300D03*
X1740019Y508600D03*
X1735019D03*
X1752000Y929200D03*
X1755010Y966285D03*
X1740019Y961355D03*
X1735019D03*
X1738863Y985225D03*
X1755900Y1014600D03*
X1740499Y1008223D03*
X1749863Y1003925D03*
X1756100Y1004362D03*
X1746030Y1004209D03*
X1737241Y997843D03*
X1740363Y989225D03*
X1733245Y1115503D03*
X1751400Y1173900D03*
X1732768Y1141697D03*
X1748100Y1153673D03*
X1718117Y1152553D03*
X1723117D03*
X1755900Y1212704D03*
X1740000Y1346900D03*
X1808850Y162661D03*
X1808600Y187911D03*
Y640667D03*
X1808850Y615417D03*
X1766721Y720500D03*
X1813851Y927406D03*
X1768692Y966073D03*
X1797463Y968652D03*
X1806077Y961860D03*
X1782666Y961344D03*
X1777666D03*
X1783778Y970371D03*
X1774863Y1024725D03*
X1788726Y1034726D03*
X1778863Y1005725D03*
X1787163Y1009741D03*
X1772863Y1005304D03*
X1778963Y999125D03*
X1772263Y995925D03*
X1812050Y1071223D03*
X1805250Y1067973D03*
X1841021Y152968D03*
X1845517Y158475D03*
X1856219Y201661D03*
X1823350Y175161D03*
X1827796Y166019D03*
X1831350Y210661D03*
Y205661D03*
Y200661D03*
X1850669Y219661D03*
X1846169D03*
X1841669D03*
X1824850Y227661D03*
X1819850D03*
X1814850D03*
X1831350Y215661D03*
X1834896Y518597D03*
X1849045Y517435D03*
X1859232Y508600D03*
X1823350Y627917D03*
X1827667Y618703D03*
X1840855Y606200D03*
X1845417Y611231D03*
X1841669Y672417D03*
X1846169D03*
X1850669D03*
X1814850Y680417D03*
X1819850D03*
X1824850D03*
X1856219Y654417D03*
X1831350Y658417D03*
Y663417D03*
Y668417D03*
X1831300Y652600D03*
X1855676Y800787D03*
X1824170Y886349D03*
X1819541Y921500D03*
X1823937Y890883D03*
X1821152Y907899D03*
X1823350Y1080673D03*
X1858046Y1092779D03*
X1836953Y1103391D03*
X1850363Y1115037D03*
X1847506Y1118794D03*
X1851565Y1118784D03*
X1850280Y1111373D03*
X1816046Y1098532D03*
X1836200Y1130000D03*
X1828850Y1106173D03*
Y1111173D03*
Y1116173D03*
Y1121173D03*
X1824850Y1133173D03*
X1814850D03*
X1819850D03*
X1840585Y1151653D03*
X1836400Y1151900D03*
X1842000Y1344700D03*
X1869500Y179134D03*
X1876938Y181062D03*
X1865669Y201661D03*
X1870669D03*
X1875669D03*
X1880669D03*
X1864232Y508600D03*
X1869500Y633500D03*
X1878900Y637000D03*
X1879669Y652917D03*
X1874669D03*
X1869669D03*
X1864669D03*
X1884800Y890750D03*
X1902441Y888500D03*
X1896943Y894350D03*
X1891676Y917759D03*
X1884500Y912500D03*
X1904000Y933500D03*
Y929000D03*
Y925000D03*
X1906500Y893400D03*
X1909358Y897500D03*
X1904000Y938000D03*
X1873001Y901396D03*
X1904000Y921000D03*
X1872190Y936766D03*
X1867963Y996425D03*
X1887402Y1050193D03*
X1872162Y1055426D03*
X1864617Y1040934D03*
X1888085Y1059938D03*
X1876662Y1055426D03*
X1864833Y1091419D03*
X1870779Y1091763D03*
X1875779D03*
X1880779D03*
X1873500Y1329000D03*
X1911676Y893469D03*
G54D32*
X429724Y68307D03*
X458071D03*
X443898D03*
X429724Y116339D03*
Y96654D03*
Y102166D03*
Y110827D03*
Y87993D03*
Y82481D03*
Y73819D03*
X443898Y116339D03*
X458071D03*
X436811Y114764D03*
X450984D03*
X443898Y96654D03*
X458071D03*
X443898Y102166D03*
X458071D03*
X436811Y100591D03*
X450984D03*
X436811Y106103D03*
X450984D03*
X443898Y110827D03*
X458071D03*
Y87993D03*
Y82481D03*
X450984Y91930D03*
Y86418D03*
X443898Y87993D03*
Y82481D03*
X436811Y91930D03*
Y86418D03*
X458071Y73819D03*
X450984Y77756D03*
Y72245D03*
X443898Y73819D03*
X436811Y77756D03*
Y72245D03*
Y120276D03*
X450984D03*
X472244Y68307D03*
X465157Y114764D03*
X472244Y116339D03*
X479331Y114764D03*
X465157Y100591D03*
Y106103D03*
X472244Y96654D03*
Y102166D03*
X479331Y100591D03*
Y106103D03*
X472244Y110827D03*
X479331Y91930D03*
Y86418D03*
X472244Y87993D03*
Y82481D03*
X465157Y91930D03*
Y86418D03*
X479331Y77756D03*
Y72245D03*
X472244Y73819D03*
X465157Y77756D03*
Y72245D03*
Y120276D03*
X479331D03*
X514764Y68307D03*
X543110D03*
X528937D03*
X557283D03*
X514764Y116339D03*
Y110827D03*
Y102166D03*
Y96654D03*
Y87993D03*
Y82481D03*
Y73819D03*
X550197Y114764D03*
X536024D03*
X521850D03*
X543110Y116339D03*
X528937D03*
X543110Y110827D03*
X528937D03*
X550197Y106103D03*
X536024D03*
X521850D03*
X550197Y100591D03*
X536024D03*
X521850D03*
X543110Y102166D03*
X528937D03*
X543110Y96654D03*
X528937D03*
X550197Y91930D03*
Y86418D03*
X543110Y87993D03*
Y82481D03*
X536024Y91930D03*
Y86418D03*
X528937Y87993D03*
Y82481D03*
X521850Y91930D03*
Y86418D03*
X550197Y77756D03*
Y72245D03*
X543110Y73819D03*
X536024Y77756D03*
Y72245D03*
X528937Y73819D03*
X521850Y77756D03*
Y72245D03*
X557283Y116339D03*
Y110827D03*
Y102166D03*
Y96654D03*
Y87993D03*
Y82481D03*
Y73819D03*
X550197Y120276D03*
X536024D03*
X521850D03*
X564370Y114764D03*
Y106103D03*
Y100591D03*
Y91930D03*
Y86418D03*
Y77756D03*
Y72245D03*
Y120276D03*
X833859Y1598425D03*
Y1603937D03*
Y1612599D03*
X840945Y1602363D03*
X826772D03*
X840945Y1607874D03*
X826772D03*
X840945Y1616536D03*
X826772D03*
X833859Y1618111D03*
Y1626772D03*
Y1632284D03*
Y1640945D03*
Y1646457D03*
X840945Y1622048D03*
X826772D03*
X840945Y1630709D03*
X826772D03*
X840945Y1636221D03*
X826772D03*
X840945Y1644882D03*
X826772D03*
X840945Y1650394D03*
X826772D03*
X876378Y1598425D03*
X862205D03*
X848032D03*
X876378Y1603937D03*
X862205D03*
X848032D03*
X876378Y1612599D03*
X862205D03*
X848032D03*
X890552Y1602363D03*
X869292D03*
X855118D03*
X890552Y1607874D03*
X869292D03*
X855118D03*
X890552Y1612205D03*
Y1616536D03*
X869292D03*
X855118D03*
X876378Y1618111D03*
X862205D03*
X848032D03*
X876378Y1626772D03*
X862205D03*
X848032D03*
X876378Y1632284D03*
X862205D03*
X848032D03*
X876378Y1640945D03*
X862205D03*
X848032D03*
X876378Y1646457D03*
X862205D03*
X848032D03*
X890552Y1622048D03*
X869292D03*
X855118D03*
X890552Y1626378D03*
Y1630709D03*
X869292D03*
X855118D03*
X890552Y1636221D03*
X869292D03*
X855118D03*
X890552Y1640551D03*
Y1644882D03*
X869292D03*
X855118D03*
X890552Y1650394D03*
X869292D03*
X855118D03*
X911811Y1603937D03*
Y1608268D03*
Y1612599D03*
X904725Y1602363D03*
Y1607874D03*
Y1612205D03*
Y1616536D03*
X911811Y1594095D03*
Y1598425D03*
X904725Y1598032D03*
X897638Y1598425D03*
Y1603937D03*
Y1608268D03*
Y1612599D03*
X911811Y1632284D03*
Y1636614D03*
Y1640945D03*
Y1646457D03*
Y1650788D03*
X904725Y1630709D03*
Y1636221D03*
Y1640551D03*
Y1644882D03*
Y1650394D03*
X911811Y1618111D03*
Y1622441D03*
Y1626772D03*
X904725Y1622048D03*
Y1626378D03*
X897638Y1618111D03*
Y1622441D03*
Y1626772D03*
Y1632284D03*
Y1636614D03*
Y1640945D03*
Y1646457D03*
Y1650788D03*
X1095420Y988592D03*
X1100932D03*
X1109593D03*
X1115105D03*
X1123766D03*
X1129278D03*
X1099357Y995678D03*
X1104869D03*
X1113530D03*
X1119042D03*
X1127703D03*
X1133215D03*
X1095420Y1002765D03*
X1100932D03*
X1109593D03*
X1115105D03*
X1123766D03*
X1129278D03*
X1099357Y1009852D03*
X1104869D03*
X1113530D03*
X1119042D03*
X1127703D03*
X1133215D03*
X1095420Y1016938D03*
X1100932D03*
X1109593D03*
X1115105D03*
X1123766D03*
X1129278D03*
X1099357Y1024025D03*
X1104869D03*
X1113530D03*
X1119042D03*
X1127703D03*
X1133215D03*
X1095420Y1031111D03*
X1100932D03*
X1109593D03*
X1115105D03*
X1123766D03*
X1129278D03*
X1099357Y1038198D03*
X1104869D03*
X1113530D03*
X1119042D03*
X1127703D03*
X1133215D03*
X1095420Y1160257D03*
Y1174430D03*
X1100932Y1160257D03*
Y1174430D03*
X1109593Y1160257D03*
Y1174430D03*
X1115105Y1160257D03*
Y1174430D03*
X1123766Y1160257D03*
Y1174430D03*
X1129278Y1160257D03*
Y1174430D03*
X1099357Y1167343D03*
X1104869D03*
X1113530D03*
X1119042D03*
X1127703D03*
X1133215D03*
X1095420Y1188603D03*
Y1202776D03*
Y1216949D03*
X1100932Y1188603D03*
Y1202776D03*
Y1216949D03*
X1109593Y1188603D03*
Y1202776D03*
Y1216949D03*
X1115105Y1188603D03*
Y1202776D03*
Y1216949D03*
X1123766Y1188603D03*
Y1202776D03*
Y1216949D03*
X1129278Y1188603D03*
Y1202776D03*
Y1216949D03*
X1099357Y1181516D03*
Y1195690D03*
Y1209863D03*
Y1224036D03*
X1104869Y1181516D03*
Y1195690D03*
Y1209863D03*
Y1224036D03*
X1113530Y1181516D03*
Y1195690D03*
Y1209863D03*
Y1224036D03*
X1119042Y1181516D03*
Y1195690D03*
Y1209863D03*
Y1224036D03*
X1127703Y1181516D03*
Y1195690D03*
Y1209863D03*
Y1224036D03*
X1133215Y1181516D03*
Y1195690D03*
Y1209863D03*
Y1224036D03*
X1095420Y1231123D03*
Y1245296D03*
Y1259469D03*
Y1273642D03*
X1100932Y1231123D03*
Y1245296D03*
Y1259469D03*
Y1273642D03*
X1109593Y1231123D03*
Y1245296D03*
Y1259469D03*
Y1273642D03*
X1115105Y1231123D03*
Y1245296D03*
Y1259469D03*
Y1273642D03*
X1123766Y1231123D03*
Y1245296D03*
Y1259469D03*
Y1273642D03*
X1129278Y1231123D03*
Y1245296D03*
Y1259469D03*
Y1273642D03*
X1099357Y1238209D03*
Y1252382D03*
Y1266556D03*
X1104869Y1238209D03*
Y1252382D03*
Y1266556D03*
X1113530Y1238209D03*
Y1252382D03*
Y1266556D03*
X1119042Y1238209D03*
Y1252382D03*
Y1266556D03*
X1127703Y1238209D03*
Y1252382D03*
Y1266556D03*
X1133215Y1238209D03*
Y1252382D03*
Y1266556D03*
X1095420Y1287816D03*
Y1301989D03*
Y1316162D03*
X1100932Y1287816D03*
Y1301989D03*
Y1316162D03*
X1109593Y1287816D03*
Y1301989D03*
Y1316162D03*
X1115105Y1287816D03*
Y1301989D03*
Y1316162D03*
X1123766Y1287816D03*
Y1301989D03*
Y1316162D03*
X1129278Y1287816D03*
Y1301989D03*
Y1316162D03*
X1099357Y1280729D03*
Y1294902D03*
Y1309075D03*
Y1323249D03*
X1104869Y1280729D03*
Y1294902D03*
Y1309075D03*
Y1323249D03*
X1113530Y1280729D03*
Y1294902D03*
Y1309075D03*
Y1323249D03*
X1119042Y1280729D03*
Y1294902D03*
Y1309075D03*
Y1323249D03*
X1127703Y1280729D03*
Y1294902D03*
Y1309075D03*
Y1323249D03*
X1133215Y1280729D03*
Y1294902D03*
Y1309075D03*
Y1323249D03*
X1095420Y1330335D03*
Y1344508D03*
Y1358682D03*
Y1372855D03*
X1100932Y1330335D03*
Y1344508D03*
Y1358682D03*
Y1372855D03*
X1109593Y1330335D03*
Y1344508D03*
Y1358682D03*
Y1372855D03*
X1115105Y1330335D03*
Y1344508D03*
Y1358682D03*
Y1372855D03*
X1123766Y1330335D03*
Y1344508D03*
Y1358682D03*
Y1372855D03*
X1129278Y1330335D03*
Y1344508D03*
Y1358682D03*
Y1372855D03*
X1099357Y1337422D03*
Y1351595D03*
Y1365768D03*
X1104869Y1337422D03*
Y1351595D03*
Y1365768D03*
X1113530Y1337422D03*
Y1351595D03*
Y1365768D03*
X1119042Y1337422D03*
Y1351595D03*
Y1365768D03*
X1127703Y1337422D03*
Y1351595D03*
Y1365768D03*
X1133215Y1337422D03*
Y1351595D03*
Y1365768D03*
X1095420Y1387028D03*
Y1401201D03*
X1100932Y1387028D03*
Y1401201D03*
X1109593Y1387028D03*
Y1401201D03*
X1115105Y1387028D03*
Y1401201D03*
X1123766Y1387028D03*
Y1401201D03*
X1129278Y1387028D03*
Y1401201D03*
X1099357Y1379942D03*
Y1394115D03*
Y1408288D03*
X1104869Y1379942D03*
Y1394115D03*
Y1408288D03*
X1113530Y1379942D03*
Y1394115D03*
Y1408288D03*
X1119042Y1379942D03*
Y1394115D03*
Y1408288D03*
X1127703Y1379942D03*
Y1394115D03*
Y1408288D03*
X1133215Y1379942D03*
Y1394115D03*
Y1408288D03*
X1398228Y68307D03*
X1426575D03*
X1412402D03*
X1398228Y116339D03*
Y96654D03*
Y102166D03*
Y110827D03*
Y87993D03*
Y82481D03*
Y73819D03*
X1412402Y116339D03*
X1426575D03*
X1405315Y114764D03*
X1419488D03*
X1412402Y96654D03*
X1426575D03*
X1412402Y102166D03*
X1426575D03*
X1405315Y100591D03*
X1419488D03*
X1405315Y106103D03*
X1419488D03*
X1412402Y110827D03*
X1426575D03*
Y87993D03*
Y82481D03*
X1419488Y91930D03*
Y86418D03*
X1412402Y87993D03*
Y82481D03*
X1405315Y91930D03*
Y86418D03*
X1426575Y73819D03*
X1419488Y77756D03*
Y72245D03*
X1412402Y73819D03*
X1405315Y77756D03*
Y72245D03*
Y120276D03*
X1419488D03*
X1440748Y68307D03*
X1433661Y114764D03*
X1440748Y116339D03*
X1447835Y114764D03*
X1433661Y100591D03*
Y106103D03*
X1440748Y96654D03*
Y102166D03*
X1447835Y100591D03*
Y106103D03*
X1440748Y110827D03*
X1447835Y91930D03*
Y86418D03*
X1440748Y87993D03*
Y82481D03*
X1433661Y91930D03*
Y86418D03*
X1447835Y77756D03*
Y72245D03*
X1440748Y73819D03*
X1433661Y77756D03*
Y72245D03*
Y120276D03*
X1447835D03*
X1483268Y68307D03*
X1511614D03*
X1497441D03*
X1483268Y116339D03*
Y110827D03*
Y102166D03*
Y96654D03*
Y87993D03*
Y82481D03*
Y73819D03*
X1518701Y114764D03*
X1504528D03*
X1490354D03*
X1511614Y116339D03*
X1497441D03*
X1511614Y110827D03*
X1497441D03*
X1518701Y106103D03*
X1504528D03*
X1490354D03*
X1518701Y100591D03*
X1504528D03*
X1490354D03*
X1511614Y102166D03*
X1497441D03*
X1511614Y96654D03*
X1497441D03*
X1518701Y91930D03*
Y86418D03*
X1511614Y87993D03*
Y82481D03*
X1504528Y91930D03*
Y86418D03*
X1497441Y87993D03*
Y82481D03*
X1490354Y91930D03*
Y86418D03*
X1518701Y77756D03*
Y72245D03*
X1511614Y73819D03*
X1504528Y77756D03*
Y72245D03*
X1497441Y73819D03*
X1490354Y77756D03*
Y72245D03*
X1518701Y120276D03*
X1504528D03*
X1490354D03*
X1525787Y68307D03*
X1532874Y114764D03*
X1525787Y116339D03*
Y110827D03*
X1532874Y106103D03*
Y100591D03*
X1525787Y102166D03*
Y96654D03*
X1532874Y91930D03*
Y86418D03*
X1525787Y87993D03*
Y82481D03*
X1532874Y77756D03*
Y72245D03*
X1525787Y73819D03*
X1532874Y120276D03*
G54D41*
X988795Y1571058D03*
Y1576658D03*
X1026106Y1545595D03*
Y1539995D03*
X1031706Y1545595D03*
Y1539995D03*
X1020574Y1540059D03*
Y1545659D03*
X1039758Y1559605D03*
X1014974Y1540059D03*
Y1545659D03*
X1039358Y1565405D03*
X1033717Y1563634D03*
X1028223Y1563763D03*
X1022623D03*
X994305Y1566342D03*
X1017023Y1563763D03*
X1011476Y1565175D03*
X1005658Y1565005D03*
X1000058D03*
X1039958Y1553705D03*
Y1548105D03*
Y1542505D03*
X1039358Y1571005D03*
Y1576605D03*
X1005658Y1575905D03*
X1033917Y1574834D03*
X1033717Y1569234D03*
X1000058Y1575905D03*
X1028423Y1574963D03*
X1028223Y1569363D03*
X994460Y1577240D03*
X1022823Y1574963D03*
X1022623Y1569363D03*
X1017223Y1574963D03*
X1017023Y1569363D03*
X994305Y1571942D03*
X1011676Y1576375D03*
X1011476Y1570775D03*
X1005658Y1570605D03*
X1000058D03*
X1078358Y1561105D03*
Y1566705D03*
X1072758Y1561105D03*
Y1566705D03*
X1067158Y1561105D03*
Y1566705D03*
X1061558Y1561105D03*
Y1566705D03*
X1055768Y1566675D03*
X1055418Y1560785D03*
X1055618Y1554885D03*
Y1549285D03*
Y1543685D03*
X1078358Y1572305D03*
X1072758D03*
X1067158D03*
X1061558D03*
X1055768Y1572275D03*
Y1577875D03*
G54D20*
X111024Y302303D03*
Y755059D03*
Y1207815D03*
X235236Y302303D03*
Y755059D03*
Y1207815D03*
X359449Y302303D03*
Y755059D03*
Y1207815D03*
X483661Y302303D03*
Y755059D03*
Y1207815D03*
X607874Y302303D03*
Y755059D03*
Y1207815D03*
X732087Y302303D03*
Y755059D03*
Y1207815D03*
X1098524Y-115157D03*
X1281693Y302303D03*
Y755059D03*
Y1207815D03*
X1405906Y302303D03*
Y755059D03*
Y1207815D03*
X1530118Y302303D03*
Y755059D03*
Y1207815D03*
X1654331Y302303D03*
Y755059D03*
Y1207815D03*
X1778543Y302303D03*
Y755059D03*
Y1207815D03*
X1902756Y302303D03*
Y755059D03*
Y1207815D03*
G54D22*
X119763Y550725D03*
Y546225D03*
Y555225D03*
X124263Y546225D03*
Y550725D03*
Y555225D03*
X141978Y958572D03*
X142006Y978425D03*
X209863Y566625D03*
X199102Y969717D03*
Y974717D03*
X183584Y974789D03*
Y969789D03*
X199392Y985113D03*
X183551Y984789D03*
X212063Y976725D03*
X203063D03*
X207563D03*
X216563D03*
X212063Y981725D03*
X216563D03*
X207563D03*
X203063D03*
X199392Y990113D03*
X183551Y989789D03*
X250650Y556997D03*
Y561997D03*
X265545Y556794D03*
Y561794D03*
X250661Y572936D03*
Y577936D03*
X265590Y572801D03*
Y577801D03*
X225563Y976725D03*
X221063D03*
X225563Y981725D03*
X221063D03*
X269763Y569725D03*
X287763D03*
X292263D03*
X274263D03*
X283263D03*
X278763D03*
X283263Y564725D03*
X287763D03*
X292263D03*
X274263D03*
X269763D03*
X278763D03*
X637592Y593186D03*
X641792D03*
Y597386D03*
X637592D03*
X633392Y593186D03*
Y597386D03*
X629192Y593186D03*
Y597386D03*
X641792Y605786D03*
Y601586D03*
X637592D03*
Y605786D03*
X633392D03*
Y601586D03*
X629192D03*
Y605786D03*
X675913Y586555D03*
Y592955D03*
Y598155D03*
X672082Y582834D03*
X666882D03*
X661682D03*
X656482D03*
X695413Y600755D03*
X699613D03*
X669482Y613934D03*
Y609734D03*
X665282D03*
Y613934D03*
X661082D03*
Y609734D03*
X656882Y613934D03*
Y609734D03*
X675913Y603355D03*
X695413Y604955D03*
X691213Y613355D03*
X695413D03*
X699613D03*
X691213Y609155D03*
X695413D03*
X699613Y604955D03*
Y609155D03*
X703813Y592355D03*
Y596555D03*
Y600755D03*
Y613355D03*
Y609155D03*
Y604955D03*
X1370200Y550500D03*
X1366000D03*
X1378100Y530200D03*
Y534400D03*
X1365500Y538600D03*
X1369700D03*
X1365500Y534400D03*
X1369700D03*
X1373900D03*
X1365500Y530200D03*
X1369700D03*
X1373900D03*
X1375900Y568500D03*
X1366000Y563100D03*
X1370200D03*
Y554700D03*
X1366000D03*
X1370200Y558900D03*
X1366000D03*
X1373700Y582900D03*
X1369500D03*
X1377900Y587100D03*
Y591300D03*
Y595500D03*
X1373700D03*
Y591300D03*
Y587100D03*
X1369500Y595500D03*
Y591300D03*
Y587100D03*
X1377900Y599700D03*
X1373700D03*
X1369500D03*
X1396500Y549500D03*
X1386500Y534400D03*
Y530200D03*
X1382300D03*
Y534400D03*
X1396500Y559900D03*
Y554700D03*
Y565100D03*
X1393000Y568500D03*
X1387300D03*
X1381600D03*
X1382100Y587100D03*
X1386300D03*
X1434441Y590424D03*
X1434581Y586136D03*
X1697261Y1004347D03*
X1692761D03*
Y999847D03*
Y995347D03*
X1697261D03*
Y999847D03*
X1783806Y989468D03*
X1862652Y846508D03*
X1850263Y964540D03*
X1850370Y960239D03*
X1845870D03*
X1845763Y964540D03*
Y956040D03*
X1850263D03*
X1825741Y969210D03*
Y974210D03*
X1840683Y969318D03*
Y974318D03*
X1825744Y986011D03*
X1840578Y985885D03*
X1844863Y983125D03*
X1853863D03*
X1858363D03*
X1849363D03*
X1862863D03*
X1853863Y978125D03*
X1844863D03*
X1849363D03*
X1862863D03*
X1858363D03*
X1825744Y991011D03*
X1840578Y990885D03*
X1873099Y817150D03*
X1878099D03*
X1873099Y821650D03*
X1878099D03*
X1873099Y826150D03*
X1878099D03*
X1877512Y831377D03*
X1882512D03*
X1865202Y831559D03*
X1873012Y831377D03*
X1878099Y812650D03*
X1873099D03*
X1878099Y808150D03*
X1873099D03*
X1878099Y803650D03*
X1873099D03*
X1878373Y846472D03*
X1883373D03*
X1867652Y846508D03*
X1867363Y983125D03*
Y978125D03*
G54D19*
X111024Y153681D03*
Y606437D03*
Y1059193D03*
X235236Y153681D03*
Y606437D03*
Y1059193D03*
X359449Y153681D03*
Y606437D03*
Y1059193D03*
X483661Y153681D03*
Y606437D03*
Y1059193D03*
X607874Y153681D03*
Y606437D03*
Y1059193D03*
X732087Y153681D03*
Y606437D03*
Y1059193D03*
X949902Y-115157D03*
X1281693Y153681D03*
Y606437D03*
Y1059193D03*
X1405906Y153681D03*
Y606437D03*
Y1059193D03*
X1530118Y153681D03*
Y606437D03*
Y1059193D03*
X1654331Y153681D03*
Y606437D03*
Y1059193D03*
X1778543Y153681D03*
Y606437D03*
Y1059193D03*
X1902756Y153681D03*
Y606437D03*
Y1059193D03*
G54D37*
X929331Y16536D03*
X937205Y20473D03*
Y12599D03*
Y67717D03*
X929331Y48032D03*
Y32284D03*
X937205Y44095D03*
Y36221D03*
Y28347D03*
X929331Y103150D03*
Y87402D03*
Y71654D03*
X937205Y114961D03*
Y99213D03*
Y83465D03*
X929331Y166142D03*
Y150394D03*
Y134646D03*
Y118898D03*
X937205Y162205D03*
Y146457D03*
Y130709D03*
X929331Y213386D03*
Y197638D03*
Y181890D03*
X937205Y209449D03*
Y193701D03*
Y177953D03*
X929331Y260630D03*
Y244882D03*
Y229134D03*
X937205Y256693D03*
Y240945D03*
Y225197D03*
X929331Y307874D03*
Y292126D03*
Y276378D03*
X937205Y303937D03*
Y288189D03*
Y272441D03*
X929331Y339371D03*
Y323622D03*
X937205Y335434D03*
Y319685D03*
X929331Y395669D03*
X937205Y407480D03*
Y399606D03*
Y391732D03*
X929331Y450787D03*
X937205Y446850D03*
X929331Y427165D03*
Y419291D03*
Y411417D03*
X937205Y431102D03*
Y423228D03*
Y415354D03*
X929331Y498031D03*
Y482283D03*
Y466535D03*
X937205Y494094D03*
Y478346D03*
Y462598D03*
X929331Y545275D03*
Y529527D03*
Y513779D03*
X937205Y541338D03*
Y525590D03*
Y509842D03*
X929331Y592519D03*
Y576771D03*
Y561023D03*
X937205Y588582D03*
Y572834D03*
Y557086D03*
X929331Y639763D03*
Y624015D03*
Y608267D03*
X937205Y635826D03*
Y620078D03*
Y604330D03*
X929331Y687007D03*
Y671259D03*
Y655511D03*
X937205Y683070D03*
Y667322D03*
Y651574D03*
X929331Y718504D03*
Y702755D03*
X937205Y714567D03*
Y698818D03*
X954921Y16536D03*
X947047Y20473D03*
Y12599D03*
X954921Y63780D03*
X947047Y67717D03*
X954921Y40158D03*
Y32284D03*
X947047Y51969D03*
Y44095D03*
Y36221D03*
Y28347D03*
X954921Y111024D03*
Y95276D03*
Y79528D03*
X947047Y107087D03*
Y91339D03*
Y75591D03*
X954921Y158268D03*
Y142520D03*
Y126772D03*
X947047Y154331D03*
Y138583D03*
Y122835D03*
X954921Y205512D03*
Y189764D03*
Y174016D03*
X947047Y201575D03*
Y185827D03*
Y170079D03*
X954921Y252756D03*
Y237008D03*
Y221260D03*
X947047Y248819D03*
Y233071D03*
Y217323D03*
X954921Y300000D03*
Y284252D03*
Y268504D03*
X947047Y296063D03*
Y280315D03*
Y264567D03*
X954921Y339371D03*
Y331496D03*
Y315748D03*
X947047Y327559D03*
Y311811D03*
X954921Y395669D03*
X947047Y407480D03*
Y399606D03*
Y391732D03*
X954921Y442913D03*
X947047Y454724D03*
X954921Y427165D03*
Y419291D03*
Y411417D03*
X947047Y431102D03*
Y423228D03*
X954921Y490157D03*
Y474409D03*
Y458661D03*
X947047Y501968D03*
Y486220D03*
Y470472D03*
X954921Y553149D03*
Y537401D03*
Y521653D03*
Y505905D03*
X947047Y549212D03*
Y533464D03*
Y517716D03*
X954921Y600393D03*
Y584645D03*
Y568897D03*
X947047Y596456D03*
Y580708D03*
Y564960D03*
X954921Y647637D03*
Y631889D03*
Y616141D03*
X947047Y643700D03*
Y627952D03*
Y612204D03*
X954921Y694881D03*
Y679133D03*
Y663385D03*
X947047Y690944D03*
Y675196D03*
Y659448D03*
X954921Y710629D03*
X947047Y706692D03*
X1123031Y16536D03*
X1097441D03*
X1115157Y20473D03*
Y12599D03*
X1105315Y20473D03*
Y12599D03*
X1123031Y63780D03*
X1115157Y67717D03*
X1105315D03*
X1123031Y40158D03*
Y32284D03*
X1097441Y48032D03*
Y32284D03*
X1115157Y51969D03*
Y44095D03*
Y36221D03*
Y28347D03*
X1105315Y44095D03*
Y36221D03*
Y28347D03*
X1123031Y111024D03*
Y95276D03*
Y79528D03*
X1097441Y103150D03*
Y87402D03*
Y71654D03*
X1115157Y107087D03*
Y91339D03*
Y75591D03*
X1105315Y114961D03*
Y99213D03*
Y83465D03*
X1123031Y158268D03*
Y142520D03*
Y126772D03*
X1097441Y166142D03*
Y150394D03*
Y134646D03*
Y118898D03*
X1115157Y154331D03*
Y138583D03*
Y122835D03*
X1105315Y162205D03*
Y146457D03*
Y130709D03*
X1123031Y205512D03*
Y189764D03*
Y174016D03*
X1097441Y213386D03*
Y197638D03*
Y181890D03*
X1115157Y201575D03*
Y185827D03*
Y170079D03*
X1105315Y209449D03*
Y193701D03*
Y177953D03*
X1123031Y252756D03*
Y237008D03*
Y221260D03*
X1097441Y260630D03*
Y244882D03*
Y229134D03*
X1115157Y248819D03*
Y233071D03*
Y217323D03*
X1105315Y256693D03*
Y240945D03*
Y225197D03*
X1123031Y300000D03*
Y284252D03*
Y268504D03*
X1097441Y307874D03*
Y292126D03*
Y276378D03*
X1115157Y296063D03*
Y280315D03*
Y264567D03*
X1105315Y303937D03*
Y288189D03*
Y272441D03*
X1123031Y339371D03*
Y331496D03*
Y315748D03*
X1097441Y339371D03*
Y323622D03*
X1115157Y327559D03*
Y311811D03*
X1105315Y335434D03*
Y319685D03*
X1123031Y395669D03*
X1097441D03*
X1115157Y407480D03*
Y399606D03*
Y391732D03*
X1105315Y407480D03*
Y399606D03*
Y391732D03*
X1123031Y442913D03*
X1097441Y450787D03*
X1115157Y454724D03*
X1105315Y446850D03*
X1123031Y427165D03*
Y419291D03*
Y411417D03*
X1097441Y427165D03*
Y419291D03*
Y411417D03*
X1115157Y431102D03*
Y423228D03*
X1105315Y431102D03*
Y423228D03*
Y415354D03*
X1123031Y490157D03*
Y474409D03*
Y458661D03*
X1097441Y498031D03*
Y482283D03*
Y466535D03*
X1115157Y501968D03*
Y486220D03*
Y470472D03*
X1105315Y494094D03*
Y478346D03*
Y462598D03*
X1123031Y553149D03*
Y537401D03*
Y521653D03*
Y505905D03*
X1097441Y545275D03*
Y529527D03*
Y513779D03*
X1115157Y549212D03*
Y533464D03*
Y517716D03*
X1105315Y541338D03*
Y525590D03*
Y509842D03*
X1123031Y600393D03*
Y584645D03*
Y568897D03*
X1097441Y592519D03*
Y576771D03*
Y561023D03*
X1115157Y596456D03*
Y580708D03*
Y564960D03*
X1105315Y588582D03*
Y572834D03*
Y557086D03*
X1123031Y647637D03*
Y631889D03*
Y616141D03*
X1097441Y639763D03*
Y624015D03*
Y608267D03*
X1115157Y643700D03*
Y627952D03*
Y612204D03*
X1105315Y635826D03*
Y620078D03*
Y604330D03*
X1123031Y694881D03*
Y679133D03*
Y663385D03*
X1097441Y687007D03*
Y671259D03*
Y655511D03*
X1115157Y690944D03*
Y675196D03*
Y659448D03*
X1105315Y683070D03*
Y667322D03*
Y651574D03*
X1123031Y710629D03*
X1097441Y718504D03*
Y702755D03*
X1115157Y706692D03*
X1105315Y714567D03*
Y698818D03*
G54D42*
X974016Y1642401D03*
X986614D03*
X974016Y1636496D03*
Y1648307D03*
X986614Y1636496D03*
Y1648307D03*
X1030709Y1619764D03*
X1014961D03*
X1002362D03*
Y1613858D03*
X1014961D03*
X1030709D03*
X1002362Y1642401D03*
X1014961D03*
X1030709D03*
X1002362Y1625669D03*
Y1636496D03*
Y1648307D03*
X1014961Y1625669D03*
Y1636496D03*
Y1648307D03*
X1030709Y1625669D03*
Y1636496D03*
Y1648307D03*
X1043307Y1619764D03*
Y1613858D03*
Y1642401D03*
Y1625669D03*
Y1636496D03*
Y1648307D03*
X1101457Y1601181D03*
X1119685D03*
X1108150D03*
X1126378D03*
G54D31*
X313312Y98705D03*
X317812Y98905D03*
X385210Y1166347D03*
X450984Y124507D03*
X436811D03*
X479830D03*
X465157D03*
X550197D03*
X536023D03*
X521850D03*
X564370D03*
X753883Y929689D03*
Y937689D03*
Y945689D03*
X756250Y1140250D03*
X838521Y41568D03*
X838043Y37217D03*
X929331Y63780D03*
Y40158D03*
Y24410D03*
X937205Y51969D03*
X929331Y111024D03*
Y95276D03*
Y79528D03*
X937205Y107087D03*
Y91339D03*
Y75591D03*
X929331Y158268D03*
Y142520D03*
Y126772D03*
X937205Y154331D03*
Y138583D03*
Y122835D03*
X929331Y205512D03*
Y189764D03*
Y174016D03*
X937205Y201575D03*
Y185827D03*
Y170079D03*
X929331Y252756D03*
Y237008D03*
Y221260D03*
X937205Y248819D03*
Y233071D03*
Y217323D03*
X929331Y300000D03*
Y284252D03*
Y268504D03*
X937205Y296063D03*
Y280315D03*
Y264567D03*
X929331Y331496D03*
Y315748D03*
X937205Y327559D03*
Y311811D03*
X929331Y403543D03*
Y442913D03*
X937205Y454724D03*
X929331Y490157D03*
Y474409D03*
Y458661D03*
X937205Y501968D03*
Y486220D03*
Y470472D03*
X929331Y553149D03*
Y537401D03*
Y521653D03*
Y505905D03*
X937205Y549212D03*
Y533464D03*
Y517716D03*
X929331Y600393D03*
Y584645D03*
Y568897D03*
X937205Y596456D03*
Y580708D03*
Y564960D03*
X929331Y647637D03*
Y631889D03*
Y616141D03*
X937205Y643700D03*
Y627952D03*
Y612204D03*
X929331Y694881D03*
Y679133D03*
Y663385D03*
X937205Y690944D03*
Y675196D03*
Y659448D03*
X929331Y710629D03*
X937205Y706692D03*
X942925Y1369010D03*
X928384Y1346435D03*
X932559Y1360137D03*
X928439Y1360167D03*
X954921Y48032D03*
Y24410D03*
Y103150D03*
Y87402D03*
Y71654D03*
X947047Y114961D03*
Y99213D03*
Y83465D03*
X954921Y166142D03*
Y150394D03*
Y134646D03*
Y118898D03*
X947047Y162205D03*
Y146457D03*
Y130709D03*
X954921Y213386D03*
Y197638D03*
Y181890D03*
X947047Y209449D03*
Y193701D03*
Y177953D03*
X954921Y260630D03*
Y244882D03*
Y229134D03*
X947047Y256693D03*
Y240945D03*
Y225197D03*
X954921Y307874D03*
Y292126D03*
Y276378D03*
X947047Y303937D03*
Y288189D03*
Y272441D03*
X954921Y323622D03*
X947047Y335434D03*
Y319685D03*
X954921Y403543D03*
Y450787D03*
X947047Y446850D03*
Y415354D03*
X954921Y498031D03*
Y482283D03*
Y466535D03*
X947047Y494094D03*
Y478346D03*
Y462598D03*
X954921Y545275D03*
Y529527D03*
Y513779D03*
X947047Y541338D03*
Y525590D03*
Y509842D03*
X954921Y592519D03*
Y576771D03*
Y561023D03*
X947047Y588582D03*
Y572834D03*
Y557086D03*
X954921Y639763D03*
Y624015D03*
Y608267D03*
X947047Y635826D03*
Y620078D03*
Y604330D03*
X954921Y687007D03*
Y671259D03*
Y655511D03*
X947047Y683070D03*
Y667322D03*
Y651574D03*
X954921Y718504D03*
Y702755D03*
X947047Y714567D03*
Y698818D03*
X947125Y1369010D03*
X1034916Y-82413D03*
Y-87913D03*
X1011984Y-83066D03*
X1012174Y-88726D03*
X1050100Y392600D03*
Y397600D03*
Y402600D03*
X1044600Y392500D03*
Y397500D03*
Y402500D03*
Y407500D03*
X1050100Y407600D03*
X1044680Y921400D03*
X1097441Y63780D03*
X1123031Y48032D03*
Y24410D03*
X1097441Y40158D03*
Y24410D03*
X1105315Y51969D03*
X1123031Y103150D03*
Y87402D03*
Y71654D03*
X1097441Y111024D03*
Y95276D03*
Y79528D03*
X1115157Y114961D03*
Y99213D03*
Y83465D03*
X1105315Y107087D03*
Y91339D03*
Y75591D03*
X1123031Y166142D03*
Y150394D03*
Y134646D03*
Y118898D03*
X1097441Y158268D03*
Y142520D03*
Y126772D03*
X1115157Y162205D03*
Y146457D03*
Y130709D03*
X1105315Y154331D03*
Y138583D03*
Y122835D03*
X1123031Y213386D03*
Y197638D03*
Y181890D03*
X1097441Y205512D03*
Y189764D03*
Y174016D03*
X1115157Y209449D03*
Y193701D03*
Y177953D03*
X1105315Y201575D03*
Y185827D03*
Y170079D03*
X1123031Y260630D03*
Y244882D03*
Y229134D03*
X1097441Y252756D03*
Y237008D03*
Y221260D03*
X1115157Y256693D03*
Y240945D03*
Y225197D03*
X1105315Y248819D03*
Y233071D03*
Y217323D03*
X1123031Y307874D03*
Y292126D03*
Y276378D03*
X1097441Y300000D03*
Y284252D03*
Y268504D03*
X1115157Y303937D03*
Y288189D03*
Y272441D03*
X1105315Y296063D03*
Y280315D03*
Y264567D03*
X1123031Y323622D03*
X1097441Y331496D03*
Y315748D03*
X1115157Y335434D03*
Y319685D03*
X1105315Y327559D03*
Y311811D03*
X1123031Y403543D03*
X1097441D03*
X1123031Y450787D03*
X1097441Y442913D03*
X1115157Y446850D03*
X1105315Y454724D03*
X1115157Y415354D03*
X1123031Y498031D03*
Y482283D03*
Y466535D03*
X1097441Y490157D03*
Y474409D03*
Y458661D03*
X1115157Y494094D03*
Y478346D03*
Y462598D03*
X1105315Y501968D03*
Y486220D03*
Y470472D03*
X1123031Y545275D03*
Y529527D03*
Y513779D03*
X1097441Y553149D03*
Y537401D03*
Y521653D03*
Y505905D03*
X1115157Y541338D03*
Y525590D03*
Y509842D03*
X1105315Y549212D03*
Y533464D03*
Y517716D03*
X1123031Y592519D03*
Y576771D03*
Y561023D03*
X1097441Y600393D03*
Y584645D03*
Y568897D03*
X1115157Y588582D03*
Y572834D03*
Y557086D03*
X1105315Y596456D03*
Y580708D03*
Y564960D03*
X1123031Y639763D03*
Y624015D03*
Y608267D03*
X1097441Y647637D03*
Y631889D03*
Y616141D03*
X1115157Y635826D03*
Y620078D03*
Y604330D03*
X1105315Y643700D03*
Y627952D03*
Y612204D03*
X1123031Y687007D03*
Y671259D03*
Y655511D03*
X1097441Y694881D03*
Y679133D03*
Y663385D03*
X1115157Y683070D03*
Y667322D03*
Y651574D03*
X1105315Y690944D03*
Y675196D03*
Y659448D03*
X1123031Y718504D03*
Y702755D03*
X1097441Y710629D03*
X1115157Y714567D03*
Y698818D03*
X1105315Y706692D03*
X1119159Y878130D03*
Y873130D03*
Y868130D03*
X1116159Y870630D03*
Y875630D03*
X1259800Y631998D03*
Y619498D03*
Y1072254D03*
Y1084754D03*
X1413400Y575000D03*
X1384013Y631998D03*
Y619498D03*
Y1072254D03*
Y1084754D03*
X1447834Y124507D03*
X1504527D03*
X1490354D03*
X1518701D03*
X1508225Y631998D03*
Y619498D03*
Y1072254D03*
Y1084754D03*
X1532874Y124507D03*
X1632438Y179242D03*
Y166742D03*
Y631998D03*
Y619498D03*
Y1072254D03*
Y1084754D03*
X1756650Y179242D03*
Y166742D03*
X1731650Y631998D03*
Y619498D03*
X1756650Y1072254D03*
Y1084754D03*
X1880863Y179242D03*
Y166742D03*
Y631998D03*
Y619498D03*
Y1072254D03*
X1884835Y1067400D03*
X1880863Y1084754D03*
G54D11*
X24508Y5500D03*
X20000Y60000D03*
X5500Y61492D03*
Y56492D03*
Y51492D03*
Y46492D03*
Y41492D03*
Y66492D03*
X20000Y80000D03*
Y100000D03*
X5500Y81492D03*
Y76492D03*
Y96492D03*
Y91492D03*
Y86492D03*
Y71492D03*
Y101492D03*
Y111492D03*
Y116492D03*
Y106492D03*
X20000Y120000D03*
Y140000D03*
Y160000D03*
X5500Y126492D03*
Y121492D03*
Y141492D03*
Y151492D03*
Y161492D03*
Y156492D03*
Y146492D03*
Y131492D03*
Y136492D03*
X20000Y180000D03*
Y200000D03*
X5500Y181492D03*
Y191492D03*
Y201492D03*
Y211492D03*
Y171492D03*
Y206492D03*
Y196492D03*
Y176492D03*
Y166492D03*
Y186492D03*
X20000Y220000D03*
Y240000D03*
Y260000D03*
X5500Y231492D03*
Y241492D03*
Y251492D03*
Y261492D03*
Y221492D03*
Y256492D03*
Y246492D03*
Y226492D03*
Y216492D03*
Y236492D03*
X20000Y280000D03*
Y300000D03*
X5500Y281492D03*
Y291492D03*
Y301492D03*
Y271492D03*
Y306492D03*
Y296492D03*
Y286492D03*
Y276492D03*
Y266492D03*
X20000Y320000D03*
Y340000D03*
X5500Y331492D03*
Y341492D03*
Y351492D03*
Y311492D03*
Y321492D03*
Y356492D03*
Y346492D03*
Y336492D03*
Y326492D03*
Y316492D03*
X20000Y360000D03*
Y380000D03*
Y400000D03*
X5500Y381492D03*
Y391492D03*
Y401492D03*
Y361492D03*
Y371492D03*
Y406492D03*
Y396492D03*
Y386492D03*
Y376492D03*
Y366492D03*
X20000Y420000D03*
Y440000D03*
X5500Y451492D03*
Y441492D03*
Y431492D03*
Y421492D03*
Y411492D03*
Y416492D03*
Y436492D03*
Y446492D03*
Y426492D03*
Y501492D03*
Y456492D03*
Y496492D03*
Y531492D03*
Y551492D03*
Y541492D03*
Y521492D03*
Y511492D03*
Y536492D03*
Y546492D03*
Y506492D03*
Y516492D03*
Y526492D03*
Y581492D03*
Y591492D03*
Y571492D03*
Y561492D03*
Y586492D03*
Y596492D03*
Y556492D03*
Y566492D03*
Y576492D03*
Y631492D03*
Y641492D03*
Y621492D03*
Y611492D03*
Y601492D03*
Y636492D03*
Y646492D03*
Y606492D03*
Y616492D03*
Y626492D03*
Y681492D03*
Y691492D03*
Y671492D03*
Y661492D03*
Y651492D03*
Y686492D03*
Y696492D03*
Y656492D03*
Y666492D03*
Y676492D03*
Y731492D03*
Y741492D03*
Y721492D03*
Y711492D03*
Y701492D03*
Y736492D03*
Y706492D03*
Y716492D03*
Y726492D03*
Y781492D03*
Y791492D03*
Y771492D03*
Y761492D03*
Y751492D03*
Y786492D03*
Y746492D03*
Y756492D03*
Y766492D03*
Y776492D03*
Y831492D03*
Y841492D03*
Y821492D03*
Y811492D03*
Y801492D03*
Y836492D03*
Y796492D03*
Y806492D03*
Y816492D03*
Y826492D03*
Y881492D03*
Y871492D03*
Y861492D03*
Y851492D03*
Y886492D03*
Y846492D03*
Y856492D03*
Y866492D03*
Y876492D03*
X15000Y930000D03*
Y920000D03*
X25000Y930000D03*
Y920000D03*
X5500Y931492D03*
Y921492D03*
Y911492D03*
Y901492D03*
Y891492D03*
Y936492D03*
Y896492D03*
Y906492D03*
Y916492D03*
Y926492D03*
X15000Y980000D03*
Y970000D03*
Y960000D03*
Y950000D03*
Y940000D03*
X25000D03*
Y950000D03*
Y960000D03*
Y970000D03*
Y980000D03*
X5500Y976492D03*
Y981492D03*
Y986492D03*
Y966492D03*
Y956492D03*
Y961492D03*
Y971492D03*
Y951492D03*
Y941492D03*
Y946492D03*
X15000Y1030000D03*
Y1020000D03*
Y1010000D03*
Y1000000D03*
Y990000D03*
X25000D03*
Y1000000D03*
Y1010000D03*
Y1020000D03*
X5500Y991492D03*
Y996492D03*
Y1001492D03*
Y1006492D03*
Y1026492D03*
Y1016492D03*
Y1011492D03*
Y1021492D03*
Y1031492D03*
X25000Y1040000D03*
Y1080000D03*
Y1070000D03*
Y1060000D03*
Y1050000D03*
X5500Y1036492D03*
Y1066492D03*
Y1056492D03*
Y1046492D03*
Y1041492D03*
Y1051492D03*
Y1061492D03*
Y1071492D03*
Y1081492D03*
Y1076492D03*
X25000Y1090000D03*
X5500Y1121492D03*
Y1131492D03*
Y1111492D03*
Y1101492D03*
Y1091492D03*
Y1086492D03*
Y1096492D03*
Y1106492D03*
Y1116492D03*
Y1126492D03*
Y1171492D03*
Y1161492D03*
Y1151492D03*
Y1141492D03*
Y1136492D03*
Y1146492D03*
Y1156492D03*
Y1166492D03*
Y1176492D03*
Y1221492D03*
Y1211492D03*
Y1201492D03*
Y1191492D03*
Y1181492D03*
Y1186492D03*
Y1196492D03*
Y1206492D03*
Y1216492D03*
Y1226492D03*
X17500Y1270000D03*
Y1260000D03*
Y1250000D03*
Y1240000D03*
X5500Y1271492D03*
Y1261492D03*
Y1251492D03*
Y1241492D03*
Y1231492D03*
Y1236492D03*
Y1246492D03*
Y1256492D03*
Y1266492D03*
Y1276492D03*
X17500Y1290000D03*
Y1280000D03*
Y1300000D03*
Y1310000D03*
X5500Y1321492D03*
Y1311492D03*
Y1301492D03*
Y1291492D03*
Y1281492D03*
Y1286492D03*
Y1296492D03*
Y1306492D03*
Y1316492D03*
X17500Y1320000D03*
Y1360000D03*
Y1350000D03*
Y1330000D03*
Y1340000D03*
X8983Y1368303D03*
X13983D03*
X18983D03*
X23983D03*
X5500Y1361492D03*
Y1351492D03*
Y1341492D03*
Y1331492D03*
Y1336492D03*
Y1346492D03*
Y1356492D03*
Y1326492D03*
X60000Y20000D03*
X29508Y5500D03*
X39508D03*
X34508D03*
X44508D03*
X64508D03*
X69508D03*
X54508D03*
X49508D03*
X59508D03*
X60000Y40000D03*
X40000D03*
X60000Y60000D03*
X40000D03*
Y80000D03*
X60000D03*
Y100000D03*
X40000D03*
X60000Y120000D03*
X40000D03*
Y140000D03*
X60000D03*
Y160000D03*
X40000D03*
X38500Y202000D03*
X64487Y212761D03*
X56000Y237000D03*
X73437Y247161D03*
X49437Y254661D03*
X73437Y234661D03*
X62000Y276500D03*
X40000Y280000D03*
Y300000D03*
X60000D03*
Y320000D03*
X40000D03*
X60000Y340000D03*
X40000D03*
Y360000D03*
X35000Y446500D03*
X50500Y545500D03*
X58346Y516473D03*
X54088Y512336D03*
X39853Y512373D03*
X44111Y516510D03*
X40000Y560000D03*
Y580000D03*
Y600000D03*
Y620000D03*
X39000Y646000D03*
X30697Y679553D03*
X73437Y687417D03*
X64487Y665417D03*
X31043Y689115D03*
X30676Y663764D03*
X49500Y729000D03*
X49437Y707417D03*
X73437Y699917D03*
X31064Y704904D03*
X69500Y777000D03*
X51000Y755500D03*
X38500Y800500D03*
X39000Y834500D03*
X49000Y811000D03*
X51000Y846000D03*
X40000Y930000D03*
Y920000D03*
Y970000D03*
Y960000D03*
Y950000D03*
Y940000D03*
X50000Y1030000D03*
X70000Y1020000D03*
X40000Y1000000D03*
Y990000D03*
X50000Y1060000D03*
X64487Y1118173D03*
X30256Y1116731D03*
X30670Y1132472D03*
X30644Y1157871D03*
X49437Y1160173D03*
X73437Y1140173D03*
Y1152673D03*
X30623Y1142082D03*
X52000Y1186000D03*
X71500Y1205000D03*
X45800Y1306100D03*
X37500Y1360000D03*
X27500D03*
X28983Y1368303D03*
X33983D03*
X38983D03*
X43983D03*
X48983D03*
X53983D03*
X58983D03*
X63983D03*
X68983D03*
X114508Y5500D03*
X119508D03*
X104508D03*
X94508D03*
X84508D03*
X74508D03*
X79508D03*
X89508D03*
X99508D03*
X109508D03*
X80000Y80000D03*
X100000D03*
X120000D03*
Y100000D03*
X100000D03*
X80000D03*
X120000Y120000D03*
X100000D03*
X80000D03*
X86500Y157500D03*
X80000Y140000D03*
X118437Y141870D03*
X78500Y169500D03*
X111437Y195492D03*
X106937Y198543D03*
Y207992D03*
X111437Y165492D03*
Y180492D03*
X74937Y187461D03*
X92287Y194661D03*
X86637Y194861D03*
X82000Y219000D03*
X111437Y245492D03*
Y235492D03*
X106937Y217441D03*
X111437Y265492D03*
Y275492D03*
X89237Y276861D03*
X95437Y300161D03*
X96000Y336500D03*
X80000Y320000D03*
Y340000D03*
X118437Y314114D03*
X89000Y403500D03*
X100000Y420000D03*
X120000Y440000D03*
X100000D03*
Y460000D03*
X120000D03*
Y480000D03*
X100000D03*
X120000Y500000D03*
X100000D03*
X104500Y515500D03*
X120500Y524000D03*
X86500Y522000D03*
X100000Y541500D03*
X87000Y541000D03*
X89000Y557500D03*
X108500Y572000D03*
X88000Y577500D03*
X118753Y594626D03*
X88000Y602500D03*
X111437Y648248D03*
Y633248D03*
Y618248D03*
X92287Y647417D03*
X86637Y647617D03*
X74937Y640217D03*
X81500Y672000D03*
X106937Y670197D03*
X111437Y688248D03*
X106937Y660748D03*
Y651299D03*
X111437Y728248D03*
Y718248D03*
Y698248D03*
X89237Y729617D03*
X75500Y757500D03*
X94000Y789000D03*
X118437Y766870D03*
X95437Y752917D03*
X89500Y802500D03*
X90000Y858000D03*
X100000Y880000D03*
Y900000D03*
X120000D03*
Y920000D03*
X100000D03*
X120000Y940000D03*
X83100Y984800D03*
X78600D03*
X83100Y980300D03*
X78600D03*
X100000Y940000D03*
X120000Y1025000D03*
X85000Y1020000D03*
X78600Y989300D03*
X83100D03*
X74000Y1074000D03*
X85000Y1060000D03*
X111437Y1071004D03*
X118437Y1047382D03*
X81000Y1124500D03*
X106937Y1122953D03*
Y1113504D03*
Y1104055D03*
X111437Y1101004D03*
Y1086004D03*
X92287Y1100173D03*
X86637Y1100373D03*
X74937Y1092973D03*
X111437Y1171004D03*
Y1151004D03*
Y1141004D03*
X118437Y1219626D03*
X111437Y1181004D03*
X89237Y1182373D03*
X95437Y1205673D03*
X98500Y1241000D03*
X90000Y1252500D03*
X86000Y1282000D03*
X93000Y1319000D03*
X73983Y1368303D03*
X78983D03*
X83983D03*
X88983D03*
X93983D03*
X98983D03*
X107374Y1369303D03*
X112374D03*
X117374D03*
X160000Y20000D03*
X134508Y5500D03*
X124508D03*
X129508D03*
X169508D03*
X159508D03*
X149508D03*
X139508D03*
X154508D03*
X164508D03*
X144508D03*
X160000Y60000D03*
Y40000D03*
X140000D03*
Y60000D03*
X160000Y100000D03*
Y80000D03*
X140000D03*
Y100000D03*
X160000Y140000D03*
X140000D03*
X160000Y120000D03*
X140000D03*
X156500Y170500D03*
X130500Y211500D03*
X160500Y190000D03*
X160000Y180000D03*
X129000Y259000D03*
X142687Y237161D03*
X128000Y288500D03*
X160000Y280000D03*
X140000Y300000D03*
X160000D03*
X140000Y320000D03*
X160000D03*
X140000Y440000D03*
Y460000D03*
Y480000D03*
Y500000D03*
X142500Y515500D03*
X150000Y526500D03*
X164107Y512331D03*
X168365Y516368D03*
X135000Y588000D03*
X167000Y613000D03*
X147500Y605500D03*
X142687Y689917D03*
X135200Y738400D03*
X153705Y744831D03*
X153714Y720741D03*
X153757Y710653D03*
X140372Y732370D03*
X160000Y880000D03*
Y900000D03*
X140000Y920000D03*
X160000D03*
Y940000D03*
X140000D03*
X156000Y1032000D03*
X134000Y1064000D03*
X153000Y1105000D03*
X132000Y1117000D03*
X142687Y1142673D03*
X154363Y1161725D03*
X153716Y1174793D03*
X170000Y1190500D03*
X153824Y1197248D03*
X153932Y1182940D03*
X122374Y1369303D03*
X127374D03*
X132374D03*
X137374D03*
X142374D03*
X147374D03*
X152374D03*
X157374D03*
X162374D03*
X167374D03*
X200000Y20000D03*
X180000D03*
X209508Y5500D03*
X199508D03*
X189508D03*
X179508D03*
X204508D03*
X214508D03*
X174508D03*
X184508D03*
X194508D03*
X200000Y40000D03*
X180000D03*
X200000Y60000D03*
X180000D03*
Y80000D03*
X200000D03*
Y100000D03*
X180000D03*
Y120000D03*
X200000D03*
Y140000D03*
X180000D03*
X216500Y194756D03*
X210849Y194861D03*
X199149Y187461D03*
X188699Y212561D03*
X206000Y219000D03*
X180500Y237000D03*
X197649Y234661D03*
X173649Y254661D03*
X197649Y247161D03*
X180000Y300000D03*
X213449Y276861D03*
X180000Y320000D03*
Y340000D03*
X200000D03*
X178342Y512294D03*
X182600Y516331D03*
X210000Y644000D03*
X216499Y636917D03*
X199149Y631217D03*
X210849Y638617D03*
X206000Y672000D03*
X197649Y687417D03*
X213449Y729617D03*
X173649Y707417D03*
X197649Y699917D03*
X180000Y860000D03*
Y880000D03*
Y920000D03*
Y900000D03*
X215563Y1001225D03*
X203563D03*
X207563D03*
X211563D03*
X211000Y1065000D03*
X203500Y1124500D03*
X216499Y1100173D03*
X210849Y1100373D03*
X199149Y1092973D03*
X188399Y1113873D03*
X175000Y1143000D03*
X173649Y1160173D03*
X193423Y1140945D03*
X197649Y1152673D03*
X213449Y1182373D03*
X181000Y1261000D03*
X190000Y1320000D03*
X200000D03*
X210000D03*
Y1300000D03*
Y1310000D03*
X200000D03*
X190000D03*
X172374Y1369303D03*
X177374D03*
X182374D03*
X187374D03*
X192374D03*
X197374D03*
X202374D03*
X207374D03*
X212374D03*
X217374D03*
X260000Y20000D03*
X220000D03*
X240000D03*
X259508Y5500D03*
X249508D03*
X239508D03*
X229508D03*
X219508D03*
X224508D03*
X234508D03*
X244508D03*
X254508D03*
X264508D03*
X260000Y60000D03*
Y40000D03*
X240000D03*
X220000D03*
Y60000D03*
X240000D03*
X260000Y100000D03*
Y80000D03*
X240000D03*
X220000D03*
Y100000D03*
X240000D03*
X260000Y140000D03*
Y120000D03*
X240000D03*
X220000D03*
X242649Y141870D03*
X262000Y209000D03*
X235649Y195492D03*
X231991Y198543D03*
X231149Y207992D03*
X235649Y165492D03*
Y180492D03*
X253000Y260000D03*
X266899Y237161D03*
X235649Y245492D03*
Y235492D03*
X231149Y217441D03*
X255000Y280000D03*
X235649Y265492D03*
Y275492D03*
X219649Y300161D03*
X242649Y314114D03*
X220000Y360000D03*
X240000Y380000D03*
X220000D03*
Y400000D03*
X240000D03*
Y420000D03*
X220000D03*
Y440000D03*
X240000D03*
Y460000D03*
X220000D03*
Y480000D03*
X240000D03*
Y500000D03*
X220000D03*
Y520000D03*
X243051Y594626D03*
X235649Y648248D03*
Y633248D03*
Y618248D03*
X255500Y664500D03*
X231149Y670197D03*
X235649Y688248D03*
X231149Y660748D03*
Y651299D03*
X266899Y689917D03*
X235649Y728248D03*
Y718248D03*
Y698248D03*
X264739Y732114D03*
X242649Y766870D03*
X219649Y752917D03*
X248500Y788500D03*
X225000Y840000D03*
X245000D03*
X265000Y795000D03*
X225000Y815000D03*
Y880000D03*
X245000D03*
X225000Y860000D03*
X245000D03*
X225000Y900000D03*
X245000D03*
Y940000D03*
X263000Y1023000D03*
X219563Y1001225D03*
X223563D03*
X263000Y1047000D03*
X235649Y1071004D03*
X242649Y1047382D03*
X231149Y1122953D03*
Y1113504D03*
Y1104055D03*
X235649Y1101004D03*
Y1086004D03*
Y1171004D03*
Y1151004D03*
X235300Y1142700D03*
X266899Y1141173D03*
X255000Y1207500D03*
X242649Y1219626D03*
X235649Y1181004D03*
X219649Y1205673D03*
X257000Y1253000D03*
X220000Y1270000D03*
Y1320000D03*
X230000D03*
X240000D03*
X250000D03*
X260000D03*
X220000Y1280000D03*
X230000D03*
X250000Y1290000D03*
X240000D03*
X230000D03*
X220000D03*
Y1300000D03*
X230000D03*
X240000D03*
X250000D03*
X260000D03*
Y1310000D03*
X250000D03*
X240000D03*
X230000D03*
X220000D03*
X222374Y1369303D03*
X227374D03*
X232374D03*
X237374D03*
X242374D03*
X247374D03*
X252374D03*
X257374D03*
X262374D03*
X300000Y20000D03*
X280000D03*
X309508Y5500D03*
X299508D03*
X289508D03*
X279508D03*
X269508D03*
X304508D03*
X314508D03*
X274508D03*
X284508D03*
X294508D03*
X300000Y40000D03*
X280000Y60000D03*
Y40000D03*
Y100000D03*
Y80000D03*
X312355Y72855D03*
X280000Y140000D03*
Y120000D03*
X270000Y179500D03*
X285500Y189500D03*
X283000Y181000D03*
X314329Y212420D03*
X304500Y237000D03*
X297862Y254661D03*
X300000Y300000D03*
Y320000D03*
Y340000D03*
X295000Y400000D03*
Y440000D03*
Y460000D03*
X302513Y512294D03*
X306771Y516331D03*
X292536Y516368D03*
X288278Y512331D03*
X282263Y589225D03*
X270263D03*
X274263D03*
X286263D03*
X290263D03*
X278263D03*
X277000Y618500D03*
X275000Y647000D03*
X294500Y607500D03*
X284000D03*
X312912Y665417D03*
X277972Y744575D03*
X297862Y707417D03*
X277981Y720485D03*
X278024Y710397D03*
X286000Y810500D03*
X305200Y1068400D03*
X295200Y1078400D03*
Y1058400D03*
X281000Y1105000D03*
X312912Y1118273D03*
X304500Y1142500D03*
X302452Y1165162D03*
X278577Y1161725D03*
X277930Y1175001D03*
X306000Y1182500D03*
X278076Y1197355D03*
X278146Y1182940D03*
X301000Y1231000D03*
X267374Y1369303D03*
X272374D03*
X277374D03*
X282374D03*
X287374D03*
X292374D03*
X297374D03*
X302374D03*
X307374D03*
X312374D03*
X360000Y20000D03*
X340000D03*
X320000D03*
X359508Y5500D03*
X349508D03*
X339508D03*
X329508D03*
X319508D03*
X324508D03*
X334508D03*
X344508D03*
X354508D03*
X360000Y40000D03*
X340000D03*
X320000D03*
X355200Y58400D03*
X346245Y58745D03*
X353001Y81799D03*
X351000Y70700D03*
X328000Y150500D03*
X333021Y129679D03*
X359862Y165492D03*
Y180492D03*
Y195492D03*
X355362Y198543D03*
Y207992D03*
X323362Y187461D03*
X340712Y194661D03*
X335062Y194861D03*
X333500Y219000D03*
X359862Y245492D03*
Y235492D03*
X355362Y217441D03*
X321862Y234661D03*
Y247161D03*
X359862Y265492D03*
Y275492D03*
X337662Y276861D03*
X343862Y300161D03*
X352000Y331000D03*
X320000Y340000D03*
X350000Y440000D03*
X330000D03*
X350000Y500000D03*
Y480000D03*
Y460000D03*
X330000D03*
Y540000D03*
X350000D03*
Y520000D03*
X333000Y560000D03*
Y580000D03*
X350000Y560000D03*
X333000Y604000D03*
X359862Y648248D03*
Y633248D03*
Y618248D03*
X340712Y647517D03*
X335062Y647617D03*
X323362Y640217D03*
X330000Y672000D03*
X355362Y670197D03*
X359862Y688248D03*
X355362Y660748D03*
Y651299D03*
X321862Y687417D03*
X359862Y728248D03*
Y718248D03*
Y698248D03*
X337662Y729617D03*
X321862Y699917D03*
X355000Y780500D03*
X320000Y750000D03*
X330000Y770000D03*
X347000Y788500D03*
X343862Y752917D03*
X361500Y901500D03*
X330000Y900000D03*
X360000Y960000D03*
Y940000D03*
X330000Y960000D03*
X322000Y988500D03*
X362000Y1017000D03*
X328000Y1061000D03*
X359862Y1071004D03*
X355362Y1122953D03*
Y1113504D03*
Y1104055D03*
X359862Y1101004D03*
Y1086004D03*
X340812Y1100273D03*
X335062Y1100373D03*
X323362Y1092973D03*
X358518Y1171114D03*
X359862Y1151004D03*
Y1141004D03*
X321862Y1140173D03*
Y1152673D03*
X327500Y1197000D03*
X359862Y1181004D03*
X337662Y1182373D03*
X343862Y1205673D03*
X353000Y1231000D03*
X330000Y1302000D03*
X333983Y1368303D03*
X338983D03*
X343983D03*
X348983D03*
X353983D03*
X358983D03*
X363983D03*
X317374Y1369303D03*
X322374D03*
X327374D03*
X380000Y20000D03*
X395075Y18639D03*
Y13639D03*
X389508Y5500D03*
X379508D03*
X369508D03*
X364508D03*
X374508D03*
X384508D03*
X394508D03*
X380000Y60000D03*
Y40000D03*
X395075Y43639D03*
Y38639D03*
Y33639D03*
Y28639D03*
Y23639D03*
X399000Y62000D03*
X396000Y55500D03*
X396075Y50248D03*
X401000Y89000D03*
X400000Y80000D03*
X365162Y88731D03*
Y77731D03*
X388500Y153500D03*
X395500Y160500D03*
X366862Y141870D03*
X386000Y209000D03*
X390312Y237161D03*
X389000Y289000D03*
X385500Y313000D03*
X366862Y314114D03*
X390000Y500000D03*
X370000D03*
X390000Y540000D03*
Y520000D03*
X370000D03*
Y540000D03*
X389000Y594500D03*
X390000Y560000D03*
X370000D03*
X366862Y594626D03*
X395000Y631000D03*
X388000Y607000D03*
X410000Y692500D03*
X379000Y664000D03*
X391112Y689917D03*
X402129Y744503D03*
X388796Y732042D03*
X402138Y720413D03*
X402181Y710325D03*
X402500Y780500D03*
X366862Y766870D03*
X397000Y911000D03*
X380000Y960000D03*
Y940000D03*
X393500Y988500D03*
Y1017000D03*
X390000Y1055000D03*
X366862Y1047382D03*
X391112Y1142673D03*
X399474Y1166787D03*
X366862Y1219626D03*
X406037Y1192706D03*
X402403Y1188312D03*
X368983Y1368303D03*
X373983D03*
X378983D03*
X383983D03*
X388983D03*
X393983D03*
X398983D03*
X403983D03*
X408983D03*
X437124Y212661D03*
X447574Y187461D03*
X446074Y247161D03*
X422300Y254661D03*
X446074Y234661D03*
X430000Y545500D03*
X460000Y540000D03*
X426663Y512257D03*
X430921Y516294D03*
X416686Y516331D03*
X412428Y512294D03*
X460000Y600000D03*
X445000D03*
X440000Y560000D03*
X460000D03*
X440000Y613000D03*
X459274Y647617D03*
X447574Y640217D03*
X417000Y652500D03*
X454500Y672000D03*
X446074Y687417D03*
X437224Y665417D03*
X452500Y744500D03*
X437500Y744000D03*
X422074Y707417D03*
X446074Y699917D03*
X455000Y780000D03*
X445000D03*
X440000Y760000D03*
X445000Y798000D03*
X428000Y988500D03*
X424000Y1105000D03*
X418500Y1176800D03*
X437104Y1160696D03*
X450500Y1208500D03*
X424000Y1206000D03*
X454500Y1248500D03*
X460000Y1320000D03*
X440000D03*
X460000Y1300000D03*
X413983Y1368303D03*
X418983D03*
X423983D03*
X428983D03*
X433983D03*
X438983D03*
X443983D03*
X448983D03*
X453983D03*
X458983D03*
X476319Y144481D03*
X506750Y165324D03*
X480159Y201245D03*
X500184Y200328D03*
X497785Y178034D03*
X478306Y195593D03*
X461122Y194861D03*
X484074Y245492D03*
X478651Y220734D03*
X484074Y235492D03*
Y275492D03*
X481174Y265492D03*
X461874Y276861D03*
X468074Y300161D03*
X491074Y314114D03*
X470000Y400000D03*
Y380000D03*
Y430000D03*
X465000Y491000D03*
X506746Y512331D03*
X499000Y553000D03*
X491074Y594626D03*
X484074Y648248D03*
Y633248D03*
Y618248D03*
X464924Y647417D03*
X479574Y670197D03*
X484074Y688248D03*
X479574Y660748D03*
Y651299D03*
X484074Y728248D03*
Y718248D03*
Y698248D03*
X461874Y729617D03*
X461500Y769500D03*
X491074Y766870D03*
X468074Y752917D03*
X500000Y960000D03*
Y940000D03*
X480000Y960000D03*
Y940000D03*
X504000Y988500D03*
X462000D03*
X468000Y1047000D03*
X484074Y1071004D03*
X491074Y1047382D03*
X479574Y1113504D03*
Y1104055D03*
X484074Y1101004D03*
Y1086004D03*
X504724Y1118073D03*
X484074Y1171004D03*
Y1151004D03*
Y1141004D03*
X506700Y1141973D03*
X502500Y1211500D03*
X476373Y1219498D03*
X484074Y1181004D03*
X461874Y1182373D03*
X468074Y1205673D03*
X480000Y1320000D03*
X500000Y1300000D03*
X480000D03*
Y1280000D03*
X463983Y1368303D03*
X468983D03*
X473983D03*
X478983D03*
X483983D03*
X488983D03*
X493983D03*
X498983D03*
X503983D03*
X508983D03*
X519868Y242334D03*
X515500Y301000D03*
X550987Y262810D03*
X548500Y343000D03*
X515000Y322500D03*
X547500Y440000D03*
X520981Y512294D03*
X525239Y516331D03*
X511004Y516368D03*
X540000Y583000D03*
Y600000D03*
X520000D03*
X528000Y611000D03*
X532000Y623000D03*
X515324Y689917D03*
X526225Y744756D03*
X546287Y707417D03*
X512892Y732295D03*
X526277Y710578D03*
X526234Y720666D03*
X509000Y772000D03*
X555500Y852000D03*
X551500Y888000D03*
X523500Y883500D03*
X525000Y937000D03*
X525500Y967000D03*
X523000Y1045000D03*
X528500Y1073500D03*
X546287Y1160173D03*
X535320Y1152771D03*
X534874Y1139774D03*
X526523Y1177122D03*
X526501Y1166546D03*
X526388Y1197747D03*
X526367Y1183111D03*
X539000Y1309000D03*
X517374Y1369303D03*
X522374D03*
X527374D03*
X532374D03*
X537374D03*
X542374D03*
X547374D03*
X552374D03*
X557374D03*
X597051Y7699D03*
Y12699D03*
Y17699D03*
X604146Y5500D03*
X597051Y22699D03*
Y27699D03*
Y32699D03*
Y37699D03*
Y42699D03*
X589000Y64000D03*
X594000Y61500D03*
X596000Y56500D03*
X596051Y51090D03*
X603787Y207992D03*
X604517Y196263D03*
X603697Y182091D03*
X586719Y196888D03*
X568687Y187660D03*
X583487Y194861D03*
X588188Y216520D03*
X570287Y234661D03*
X563000Y217600D03*
X569009Y247887D03*
X592287Y300161D03*
X582758Y276861D03*
X590000Y342000D03*
X560000Y438500D03*
X594500Y462000D03*
X569529Y502127D03*
X592000Y595000D03*
X580000Y600000D03*
X560000D03*
X586000Y611000D03*
X589137Y647417D03*
X583487Y647617D03*
X571787Y640217D03*
X579000Y672000D03*
X603787Y670197D03*
Y660748D03*
Y651299D03*
X570287Y687417D03*
X561437Y665417D03*
X559000Y741000D03*
X586087Y729617D03*
X570287Y699917D03*
X603000Y781000D03*
X592287Y752917D03*
X604000Y897000D03*
X592000Y900500D03*
X589500Y988000D03*
X571000D03*
X575000Y1057500D03*
X586500Y1061500D03*
X586000Y1046500D03*
X575000Y1046000D03*
X561337Y1120873D03*
X583487Y1100373D03*
X571787Y1092973D03*
X589137Y1100173D03*
X603787Y1122953D03*
Y1113504D03*
Y1104055D03*
X570287Y1140173D03*
Y1152673D03*
X567500Y1189500D03*
X586087Y1182373D03*
X592287Y1205673D03*
X590000Y1247000D03*
X567374Y1369303D03*
X572374D03*
X577374D03*
X582374D03*
X587374D03*
X592374D03*
X597374D03*
X602374D03*
X562374D03*
X609146Y5500D03*
X619146D03*
X614146D03*
X629146D03*
X639146D03*
X649146D03*
X654146D03*
X644146D03*
X634146D03*
X624146D03*
X613500Y66000D03*
X634500Y77000D03*
X629024Y107633D03*
X614967Y134777D03*
X606718Y168580D03*
X639537Y237161D03*
X608287Y245492D03*
Y235492D03*
X649500Y285000D03*
X608287Y275492D03*
X607961Y263934D03*
X650000Y322500D03*
X615287Y314114D03*
X649000Y429500D03*
X643000Y549500D03*
X620153Y511994D03*
X634388Y511957D03*
X615100Y513287D03*
X638646Y515994D03*
X624411Y516031D03*
X615287Y594626D03*
X608287Y648248D03*
Y633248D03*
Y618248D03*
Y688248D03*
X639537Y689917D03*
X650659Y744673D03*
X608287Y728248D03*
Y718248D03*
Y698248D03*
X637326Y732212D03*
X650668Y720583D03*
X650711Y710495D03*
X631500Y774000D03*
X615287Y766870D03*
X642000Y889500D03*
X632000Y936000D03*
X654000Y911000D03*
X646500Y898500D03*
X634000Y988000D03*
X638500Y1046500D03*
X608287Y1071004D03*
X615287Y1047382D03*
X608287Y1101004D03*
Y1086004D03*
X643000Y1146173D03*
X608287Y1171004D03*
Y1151004D03*
Y1141004D03*
X651216Y1164051D03*
X615238Y1218951D03*
X608287Y1181004D03*
X650644Y1197038D03*
X650626Y1182447D03*
X617374Y1369303D03*
X622374D03*
X627374D03*
X632374D03*
X637374D03*
X642374D03*
X647374D03*
X652374D03*
X607374D03*
X612374D03*
X679146Y5500D03*
X689146D03*
X694146D03*
X684146D03*
X659146D03*
X669146D03*
X664146D03*
X674146D03*
X699146D03*
X700000Y60000D03*
X675000Y75500D03*
X697457Y107247D03*
X697483Y111500D03*
X661965Y106177D03*
X658500Y184500D03*
X695137Y189130D03*
X685545Y212806D03*
X689426Y236628D03*
X694500Y247161D03*
X670500Y254661D03*
X673500Y344000D03*
X698500Y415500D03*
X695500Y462500D03*
X670000Y531500D03*
X696000Y641717D03*
X694500Y687417D03*
X685550Y665417D03*
X670500Y707417D03*
X694500Y699917D03*
X691500Y778000D03*
X692500Y790500D03*
X678500Y776500D03*
X673500Y752000D03*
X696000Y1092973D03*
X685250Y1113673D03*
X667700Y1160173D03*
X694500Y1140173D03*
X692671Y1152747D03*
X668000Y1195000D03*
X680500Y1208500D03*
X698500Y1306500D03*
X667374Y1369303D03*
X672374D03*
X677374D03*
X682374D03*
X687374D03*
X692374D03*
X697374D03*
X702374D03*
X657374D03*
X662374D03*
X749146Y5500D03*
X709146D03*
X719146D03*
X729146D03*
X739146D03*
X744146D03*
X734146D03*
X724146D03*
X714146D03*
X704146D03*
X740000Y40000D03*
X720000D03*
Y60000D03*
X740000D03*
X724645Y138941D03*
X732500Y180492D03*
Y165492D03*
X728000Y207992D03*
Y198543D03*
X732100Y198373D03*
X707700Y194861D03*
X713350Y194661D03*
X728000Y217441D03*
X732500Y245492D03*
X731048Y238563D03*
X738361Y306612D03*
X732500Y275492D03*
Y265492D03*
X710300Y276861D03*
X716500Y300161D03*
X724000Y338500D03*
X748000Y368500D03*
X726000Y369000D03*
X732000Y374500D03*
Y383000D03*
X748500Y409000D03*
X721500Y462500D03*
X727500Y476000D03*
X724000Y583500D03*
X702500Y563000D03*
X739500Y594626D03*
X732500Y648248D03*
Y633248D03*
Y618248D03*
X713350Y647417D03*
X704500Y672000D03*
X728000Y670197D03*
X732500Y688248D03*
X728000Y660748D03*
Y651299D03*
X707700Y649117D03*
X732500Y728248D03*
Y718248D03*
Y698248D03*
X710300Y729617D03*
X748000Y783000D03*
X739500Y766870D03*
X716500Y752917D03*
X745000Y833000D03*
X704500Y795000D03*
X747656Y876717D03*
X709500Y894500D03*
X712000Y1046000D03*
X732500Y1071004D03*
X739500Y1047382D03*
X728000Y1122953D03*
Y1113504D03*
Y1104055D03*
X732500Y1101004D03*
Y1086004D03*
X713350Y1100173D03*
X707700Y1100373D03*
X716000Y1136000D03*
X732500Y1171004D03*
Y1151004D03*
Y1141004D03*
X739500Y1219626D03*
X732500Y1181004D03*
X710300Y1182373D03*
X716500Y1205673D03*
X747374Y1369303D03*
X742374D03*
X717374D03*
X722374D03*
X727374D03*
X732374D03*
X737374D03*
X707374D03*
X712374D03*
X795969Y-1374D03*
X759146Y5500D03*
X769146D03*
X774146D03*
X764146D03*
X754146D03*
X779146D03*
X789045Y11615D03*
X780000Y40000D03*
X760000D03*
Y60000D03*
X780000D03*
X752950Y213450D03*
X771500Y311000D03*
X764000Y439500D03*
X767500Y463500D03*
X772000Y479500D03*
X787000Y514000D03*
X798140Y630220D03*
X798210Y626440D03*
X798367Y622400D03*
X751750Y685300D03*
X793000Y828000D03*
Y851000D03*
X778000Y988500D03*
X762500D03*
X763000Y1075000D03*
X781000Y1373000D03*
X755500Y1374500D03*
X752500Y1370500D03*
X757287Y1380873D03*
Y1385873D03*
Y1390873D03*
Y1395873D03*
Y1400873D03*
Y1405873D03*
Y1410873D03*
Y1415873D03*
Y1420873D03*
X784000Y1443000D03*
X757287Y1425873D03*
Y1430873D03*
Y1435873D03*
Y1440873D03*
Y1445873D03*
X766156Y1462004D03*
X771156D03*
X790500Y1466500D03*
X786000Y1463500D03*
X756287Y1459264D03*
Y1454264D03*
X779547Y1463004D03*
X792902Y1477964D03*
Y1487964D03*
Y1497964D03*
Y1507964D03*
Y1517964D03*
Y1512964D03*
Y1472964D03*
Y1482964D03*
Y1492964D03*
Y1502964D03*
Y1562964D03*
Y1527964D03*
Y1537964D03*
Y1547964D03*
Y1557964D03*
Y1567964D03*
Y1522964D03*
Y1532964D03*
Y1542964D03*
Y1552964D03*
Y1612964D03*
Y1602964D03*
Y1592964D03*
Y1582964D03*
Y1572964D03*
Y1577964D03*
Y1587964D03*
Y1597964D03*
Y1607964D03*
X797902Y1652964D03*
X792902D03*
Y1642964D03*
Y1632964D03*
Y1622964D03*
Y1627964D03*
Y1637964D03*
Y1647964D03*
Y1617964D03*
X845961Y61762D03*
Y56762D03*
Y52762D03*
X846000Y116500D03*
X811500Y372000D03*
X800000Y400000D03*
X811500Y469500D03*
X846400Y469300D03*
X839000Y541000D03*
X839500Y560000D03*
X800867Y619400D03*
X803367Y622400D03*
X827500Y922500D03*
X839414Y1520763D03*
X833859Y1594095D03*
Y1608268D03*
X840945Y1598032D03*
X826772D03*
X840945Y1612205D03*
X826772D03*
X833859Y1622441D03*
Y1636614D03*
Y1650788D03*
X840945Y1626378D03*
X826772D03*
X840945Y1640551D03*
X826772D03*
X872642Y-140575D03*
Y-135575D03*
Y-130575D03*
Y-125575D03*
X890264Y-147256D03*
X880264D03*
X875264D03*
X885264D03*
X895264D03*
X882000Y-105500D03*
X872642Y-80575D03*
Y-120575D03*
Y-115575D03*
Y-110575D03*
Y-105575D03*
Y-100575D03*
Y-95575D03*
Y-90575D03*
Y-85575D03*
Y-30575D03*
Y-35575D03*
Y-40575D03*
Y-45575D03*
Y-50575D03*
Y-55575D03*
Y-60575D03*
Y-65575D03*
Y-70575D03*
Y-75575D03*
Y-20575D03*
Y-25575D03*
X885046Y20384D03*
X861101Y66680D03*
X862099Y61626D03*
Y56626D03*
X861961Y52762D03*
X852769Y66957D03*
X848769D03*
X856769D03*
X853961Y52762D03*
X849961D03*
X857961D03*
X874244Y37026D03*
Y44935D03*
X852769Y74957D03*
X856769D03*
X861142Y71026D03*
X852810Y71303D03*
X856810D03*
X853900Y89701D03*
X888500Y260500D03*
X850500Y266000D03*
X866000Y315000D03*
X856500Y373000D03*
X855500Y499500D03*
X871487Y463589D03*
X860092Y542405D03*
X867500Y643000D03*
X877000Y664500D03*
X868500Y665000D03*
X885600Y824400D03*
X867663Y818831D03*
X885301Y1358557D03*
X884746Y1350438D03*
X873495Y1370213D03*
X885300Y1371050D03*
X877300Y1432400D03*
X886500Y1432500D03*
X893158Y1516542D03*
X893050Y1489500D03*
X868791Y1478782D03*
X892682Y1520718D03*
X855092Y1535821D03*
X866621Y1544206D03*
X876378Y1594095D03*
X862205D03*
X848032D03*
X876378Y1608268D03*
X862205D03*
X848032D03*
X890552Y1598032D03*
X869292D03*
X855118D03*
X869292Y1612205D03*
X855118D03*
X876378Y1622441D03*
X862205D03*
X848032D03*
X876378Y1636614D03*
X862205D03*
X848032D03*
X876378Y1650788D03*
X862205D03*
X848032D03*
X869292Y1626378D03*
X855118D03*
X869292Y1640551D03*
X855118D03*
X910500Y-137500D03*
X940264Y-147256D03*
X930264D03*
X925264D03*
X935264D03*
X920264D03*
X910264D03*
X900264D03*
X905264D03*
X915264D03*
X902000Y-58000D03*
X909000Y89000D03*
X898000Y133000D03*
X911000Y305500D03*
X898000Y268000D03*
X915000Y879000D03*
X926185Y928342D03*
X924974Y933041D03*
X914876Y901029D03*
X937621Y915324D03*
X924563Y962945D03*
X919759Y970868D03*
X938009Y987330D03*
X941868Y952101D03*
X916446Y1035438D03*
X941640Y995820D03*
X929257Y1035883D03*
X932564Y1346100D03*
X904941Y1456941D03*
X918505Y1530405D03*
X918800Y1534500D03*
X897638Y1594095D03*
X960264Y-147256D03*
X950264D03*
X955264D03*
X965264D03*
X945264D03*
X990264D03*
X980264D03*
X970264D03*
X975264D03*
X985264D03*
X975500Y11500D03*
X974000Y402000D03*
Y523000D03*
X985500Y613500D03*
X978000Y677000D03*
X981580Y932678D03*
X976580Y986180D03*
X959400Y960300D03*
X987970Y1004157D03*
X955700Y1030700D03*
X977400Y1157900D03*
X977500Y1182300D03*
X962500Y1298500D03*
X988624Y1502923D03*
X951815Y1491459D03*
X1010264Y-147256D03*
X1000264D03*
X1005264D03*
X1015264D03*
X995264D03*
X1040264D03*
X1030264D03*
X1020264D03*
X1025264D03*
X1035264D03*
X1015582Y-69800D03*
X1014800Y-62100D03*
X999300Y-64400D03*
X1009100Y-48600D03*
X1035000Y-66800D03*
X1022618Y-36900D03*
X1023300Y-44200D03*
X1032053Y-34953D03*
X1038712Y-34812D03*
X1017600Y63600D03*
Y58900D03*
Y54200D03*
X993000Y108000D03*
X1036003Y93543D03*
X1038503Y97543D03*
X1033503D03*
Y102543D03*
Y107543D03*
Y112543D03*
X993000Y157000D03*
Y329000D03*
X998000Y378000D03*
X995000Y455000D03*
Y488000D03*
X1018322Y545207D03*
X1018300Y550000D03*
X993000Y635000D03*
X1025000Y817000D03*
X1028472Y834829D03*
X1027063Y850703D03*
X1014891Y943357D03*
X1013713Y974651D03*
X997694Y974940D03*
X1012494Y1033840D03*
X1018000Y1076500D03*
X1031400Y1124700D03*
X1019000Y1178000D03*
X1013400Y1137500D03*
X1021991Y1141526D03*
X1004294Y1137600D03*
X997500Y1192500D03*
X1006800Y1191200D03*
X1032500Y1248000D03*
X993500Y1317000D03*
X1031000Y1350500D03*
X1031474Y1354526D03*
X1060264Y-147256D03*
X1050264D03*
X1055264D03*
X1065264D03*
X1045264D03*
X1080264D03*
X1070264D03*
X1075264D03*
X1085264D03*
X1065621Y-85082D03*
X1084200Y-82300D03*
X1074400Y-81000D03*
X1070500Y-67900D03*
X1074400Y-39100D03*
X1079600Y-50700D03*
X1087700Y-37886D03*
X1045800Y-75936D03*
X1058333Y-72770D03*
X1061325Y-40378D03*
X1054625Y-40278D03*
X1078500Y99000D03*
X1043703Y112543D03*
Y107543D03*
Y102543D03*
X1041003Y93543D03*
X1043703Y97543D03*
X1078500Y135500D03*
X1043500Y310500D03*
X1048500Y346000D03*
X1058500Y368500D03*
X1045000Y364000D03*
X1042833Y434409D03*
X1047000Y492000D03*
X1079000Y477000D03*
X1058000D03*
X1045106Y561249D03*
X1058000Y616000D03*
X1073000Y676000D03*
X1047000Y751000D03*
X1045163Y840400D03*
X1082000Y815500D03*
X1054000Y866000D03*
X1075500Y848000D03*
X1072000Y1035000D03*
X1052000Y1054000D03*
X1054080Y1077680D03*
X1087700Y1125800D03*
X1078098Y1652768D03*
X1073098D03*
X1083098D03*
X1088098D03*
X1110264Y-147256D03*
X1100264D03*
X1090264D03*
X1105264D03*
X1095264D03*
X1130264D03*
X1120264D03*
X1115264D03*
X1125264D03*
X1135264D03*
X1134500Y-103500D03*
X1115000Y-77500D03*
X1097600Y-82462D03*
X1107700Y-76800D03*
X1114400Y-55662D03*
X1093900Y-64500D03*
X1113300Y-44100D03*
X1137446Y1024025D03*
Y1009852D03*
Y995679D03*
Y1038198D03*
X1124100Y1125100D03*
X1137446Y1167343D03*
Y1224036D03*
Y1209863D03*
Y1195690D03*
Y1181516D03*
Y1266556D03*
Y1252383D03*
Y1238209D03*
Y1309076D03*
Y1323249D03*
Y1294902D03*
Y1280729D03*
Y1365769D03*
Y1351595D03*
Y1337422D03*
Y1394115D03*
Y1408288D03*
Y1379942D03*
X1093098Y1652768D03*
X1133098D03*
X1123098D03*
X1113098D03*
X1103098D03*
X1108098D03*
X1118098D03*
X1128098D03*
X1098098D03*
X1170264Y-147256D03*
X1155264D03*
X1175602Y-137594D03*
Y-127594D03*
X1160264Y-147256D03*
X1150264D03*
X1140264D03*
X1145264D03*
X1175602Y-132594D03*
Y-142594D03*
X1165264Y-147256D03*
X1175602Y-117594D03*
Y-107594D03*
Y-97594D03*
Y-87594D03*
Y-77594D03*
Y-82594D03*
Y-92594D03*
Y-102594D03*
Y-112594D03*
Y-122594D03*
X1139500Y-58500D03*
X1150000Y-63000D03*
X1175602Y-67594D03*
Y-57594D03*
Y-47594D03*
Y-37594D03*
Y-32594D03*
Y-42594D03*
Y-52594D03*
Y-62594D03*
Y-72594D03*
Y-17594D03*
Y-27594D03*
X1180500Y4000D03*
X1176500Y-500D03*
X1175602Y-22594D03*
Y-12594D03*
Y-7594D03*
X1184088Y101360D03*
X1184141Y96794D03*
X1177500Y153500D03*
X1173500Y397000D03*
X1156500Y467000D03*
X1166500Y635000D03*
X1156500Y619000D03*
X1176835Y618934D03*
X1156500Y650000D03*
X1181000Y814000D03*
X1156500Y813000D03*
X1179000Y829500D03*
X1166500D03*
X1158500Y868500D03*
X1144580Y1078680D03*
X1172564Y1118373D03*
X1162000Y1371500D03*
X1169783Y1369303D03*
X1179783D03*
X1174783D03*
X1184783D03*
X1158673Y1417067D03*
Y1407067D03*
Y1397067D03*
Y1387067D03*
Y1377067D03*
Y1412067D03*
Y1402067D03*
Y1392067D03*
Y1382067D03*
Y1422067D03*
Y1442067D03*
Y1452067D03*
X1158500Y1468500D03*
X1158673Y1457067D03*
Y1447067D03*
Y1437067D03*
Y1427067D03*
Y1462067D03*
Y1432067D03*
X1153000Y1496000D03*
X1161000Y1474500D03*
X1166673Y1477941D03*
X1171673D03*
X1181673D03*
X1176673D03*
X1163000Y1612000D03*
X1141000Y1632000D03*
X1143098Y1652768D03*
X1183098D03*
X1173098D03*
X1163098D03*
X1153098D03*
X1158098D03*
X1168098D03*
X1178098D03*
X1138098D03*
X1148098D03*
X1228500Y12500D03*
X1191382Y5500D03*
X1196382D03*
X1186382D03*
X1201382D03*
X1211382D03*
X1221382D03*
X1231382D03*
X1226382D03*
X1216382D03*
X1206382D03*
X1204768Y64368D03*
X1199768D03*
X1209768D03*
X1204068Y50368D03*
Y45368D03*
X1203768Y60568D03*
Y55568D03*
X1224000Y104000D03*
X1199768Y69368D03*
X1204768D03*
X1209768D03*
X1204768Y85368D03*
X1199768D03*
X1209768D03*
Y89368D03*
X1199768D03*
X1204768D03*
X1186500Y220500D03*
X1224800Y225200D03*
X1219917Y239646D03*
X1232500Y541000D03*
X1197868Y730300D03*
X1194268D03*
Y723100D03*
Y726700D03*
X1197868Y723100D03*
Y726700D03*
X1192068Y712300D03*
X1195668D03*
X1192068Y715900D03*
X1195668D03*
Y719500D03*
X1192068D03*
X1188000Y753000D03*
X1192000Y869000D03*
X1232700Y950400D03*
X1229691Y1148580D03*
X1214500Y1320500D03*
X1220500Y1311000D03*
X1199783Y1369303D03*
X1209783D03*
X1219783D03*
X1229783D03*
X1189783D03*
X1224783D03*
X1214783D03*
X1204783D03*
X1194783D03*
X1194000Y1499000D03*
X1191673Y1477941D03*
X1201673D03*
X1214972Y1482642D03*
Y1517642D03*
Y1487642D03*
Y1497642D03*
Y1507642D03*
Y1512642D03*
Y1502642D03*
Y1492642D03*
X1206673Y1477941D03*
X1196673D03*
X1186673D03*
X1211673D03*
X1214972Y1567642D03*
Y1527642D03*
Y1537642D03*
Y1547642D03*
Y1557642D03*
Y1562642D03*
Y1552642D03*
Y1542642D03*
Y1532642D03*
Y1522642D03*
Y1577642D03*
Y1587642D03*
Y1597642D03*
Y1607642D03*
Y1612642D03*
Y1602642D03*
Y1592642D03*
Y1582642D03*
Y1572642D03*
Y1617642D03*
Y1627642D03*
Y1637642D03*
X1213098Y1652768D03*
X1193098D03*
X1203098D03*
X1208098D03*
X1214972Y1642642D03*
Y1632642D03*
X1188098Y1652768D03*
X1198098D03*
X1214972Y1622642D03*
Y1647642D03*
X1240500Y20000D03*
X1251382Y5500D03*
X1261382D03*
X1271382D03*
X1281382D03*
X1276382D03*
X1266382D03*
X1256382D03*
X1241382D03*
X1246382D03*
X1236382D03*
X1254000Y105000D03*
X1281500Y103500D03*
X1278900Y182823D03*
X1266400D03*
X1278421Y205974D03*
X1281603Y203340D03*
X1282106Y180492D03*
X1280800Y167200D03*
X1282287Y243489D03*
X1277606Y217441D03*
X1282106Y235492D03*
X1248193Y242618D03*
X1255600Y237300D03*
X1273200Y263700D03*
X1276200Y277400D03*
X1280000Y430000D03*
X1235796Y517450D03*
X1250011Y516707D03*
X1282106Y648248D03*
Y633248D03*
Y618248D03*
X1253800Y689600D03*
X1277606Y670197D03*
X1282106Y688248D03*
X1277606Y660748D03*
Y651299D03*
X1282106Y728248D03*
Y718248D03*
Y698248D03*
X1250475Y969248D03*
X1279081Y1071085D03*
X1277606Y1122953D03*
Y1113504D03*
Y1104055D03*
X1282106Y1101004D03*
Y1086004D03*
X1251250Y1141700D03*
X1282106Y1171004D03*
Y1151004D03*
Y1141004D03*
X1246557Y1148155D03*
X1249600Y1155800D03*
X1282106Y1181004D03*
X1257000Y1300000D03*
X1263500Y1318500D03*
X1249783Y1369303D03*
X1259783D03*
X1269783D03*
X1279783D03*
X1239783D03*
X1274783D03*
X1264783D03*
X1254783D03*
X1234783D03*
X1244783D03*
X1319000Y12000D03*
X1301382Y5500D03*
X1311382D03*
X1296382D03*
X1316382D03*
X1306382D03*
X1291382D03*
X1286382D03*
X1326382D03*
X1321382D03*
X1309000Y45500D03*
X1318500Y34500D03*
X1319100Y78800D03*
X1323521Y79179D03*
X1312999Y107280D03*
X1317661Y107896D03*
X1299569Y84272D03*
X1304563Y84309D03*
X1289000Y145400D03*
X1302074Y183779D03*
X1311200Y172661D03*
X1304293Y165909D03*
X1315838Y188804D03*
X1297507Y195492D03*
X1298700Y272800D03*
X1298500Y302900D03*
X1305000Y299400D03*
X1313000Y302900D03*
X1313915Y263541D03*
X1289000Y309500D03*
X1311000Y321000D03*
X1303500Y434000D03*
X1287000Y456000D03*
X1310000Y597000D03*
X1289106Y594626D03*
X1303800Y636417D03*
X1311200Y625417D03*
X1307500Y615417D03*
X1315400Y648017D03*
X1302500Y718917D03*
X1314000Y717417D03*
X1298500Y752417D03*
X1305000D03*
X1313000D03*
X1289106Y766870D03*
X1305000Y1041500D03*
X1289114Y1048624D03*
X1311200Y1078173D03*
X1305100Y1068173D03*
X1303800Y1089173D03*
X1315300Y1100773D03*
X1302500Y1171673D03*
X1313950Y1165990D03*
X1300065Y1206008D03*
X1305000Y1205173D03*
X1313000D03*
X1289106Y1219626D03*
X1299783Y1369303D03*
X1309783D03*
X1319783D03*
X1329783D03*
X1289783D03*
X1324783D03*
X1314783D03*
X1304783D03*
X1294783D03*
X1284783D03*
X1363579Y19821D03*
Y14821D03*
Y9821D03*
X1351382Y5500D03*
X1356382D03*
X1346382D03*
X1336382D03*
X1341382D03*
X1331382D03*
X1357500Y43500D03*
X1347500Y21000D03*
X1363579Y44821D03*
Y39821D03*
Y34821D03*
Y29821D03*
Y24821D03*
X1374000Y64500D03*
X1363579Y51618D03*
X1332500Y56500D03*
X1351201Y90099D03*
X1332934Y137712D03*
X1377463Y237100D03*
X1372000Y335000D03*
X1338000Y546500D03*
X1346363Y516578D03*
X1332148Y517321D03*
X1337500Y576500D03*
X1372272Y573560D03*
X1375463Y689917D03*
X1339500Y794000D03*
X1344000Y987500D03*
X1362000Y987000D03*
X1331070Y966090D03*
X1348796Y969488D03*
X1368935Y1123365D03*
X1365461Y1136100D03*
X1375463Y1142673D03*
X1364713Y1143791D03*
X1349783Y1369303D03*
X1359783D03*
X1369783D03*
X1339783D03*
X1374783D03*
X1364783D03*
X1354783D03*
X1344783D03*
X1334783D03*
X1413268Y146062D03*
X1401819Y207992D03*
X1394705Y195413D03*
X1406319Y180492D03*
X1405100Y166000D03*
X1403963Y245492D03*
X1385051Y218684D03*
X1406000Y236700D03*
X1426713Y266161D03*
X1426400Y307400D03*
X1406319Y275492D03*
Y265492D03*
X1400000Y406000D03*
X1427000Y380000D03*
X1425000Y480000D03*
X1405000D03*
Y460000D03*
X1385000Y480000D03*
X1396500Y511000D03*
X1383500Y509500D03*
X1413319Y594626D03*
X1406319Y648248D03*
Y633248D03*
Y618248D03*
X1421500Y664000D03*
X1401819Y670197D03*
X1406319Y688248D03*
X1401819Y660748D03*
Y651299D03*
X1426713Y718917D03*
X1406319Y728248D03*
Y718248D03*
Y698248D03*
X1422713Y752417D03*
X1398245Y766870D03*
X1395000Y791500D03*
X1390000Y955500D03*
X1390500Y1048000D03*
X1406319Y1071004D03*
X1413319Y1047382D03*
X1406319Y1086004D03*
Y1101004D03*
X1401819Y1104055D03*
X1385494Y1113504D03*
X1401819Y1122953D03*
X1406319Y1141004D03*
Y1151004D03*
Y1171004D03*
X1426713Y1171673D03*
X1406319Y1181004D03*
X1413319Y1219626D03*
X1422713Y1205173D03*
X1413000Y1241500D03*
X1387000Y1243500D03*
X1386500Y1258000D03*
X1418000Y1291500D03*
X1400000Y1320000D03*
X1420000D03*
X1399783Y1369303D03*
X1409783D03*
X1419783D03*
X1379783D03*
X1389783D03*
X1404783D03*
X1414783D03*
X1424783D03*
X1394783D03*
X1384783D03*
X1431713Y162661D03*
X1428013Y185956D03*
X1445994Y174086D03*
X1440300Y188000D03*
X1438186Y261287D03*
X1463000Y307000D03*
X1439300Y301500D03*
X1429800Y302500D03*
X1447170Y337890D03*
X1466500Y338100D03*
X1441770Y365790D03*
X1461100Y366000D03*
X1441970Y403990D03*
X1461300Y404200D03*
X1439500Y421500D03*
X1440000Y460000D03*
X1449576Y495482D03*
X1468605Y493549D03*
X1452279Y563600D03*
X1464700Y585600D03*
X1470000Y580000D03*
X1460274Y592498D03*
X1428013Y636417D03*
X1435413Y625417D03*
X1431713Y615417D03*
X1439713Y647917D03*
X1449000Y698000D03*
X1438087Y713756D03*
X1429213Y752417D03*
X1437213D03*
X1432000Y831000D03*
X1459500Y814000D03*
X1450500Y802500D03*
X1459500Y796500D03*
X1473000Y798000D03*
X1433500Y864500D03*
X1457500Y987500D03*
X1440000Y986500D03*
X1473008Y969646D03*
X1458967Y969535D03*
X1433500Y1044000D03*
X1456000D03*
X1435413Y1078173D03*
X1431713Y1068173D03*
X1428013Y1089173D03*
X1439713Y1100773D03*
X1438213Y1170173D03*
X1429213Y1205173D03*
X1437213D03*
X1458000Y1265500D03*
X1460000Y1300000D03*
Y1320000D03*
X1440000D03*
X1449783Y1369303D03*
X1459783D03*
X1469783D03*
X1429783D03*
X1439783D03*
X1444783D03*
X1454783D03*
X1464783D03*
X1474783D03*
X1434783D03*
X1515450Y181700D03*
X1502950D03*
X1498900Y235800D03*
X1505000Y378500D03*
X1520000Y421500D03*
X1479212Y535612D03*
X1494100Y526400D03*
X1507900Y539100D03*
X1481938Y512568D03*
X1509911Y553511D03*
X1478700Y579100D03*
X1502400Y554100D03*
X1494462Y692179D03*
X1515000Y789000D03*
X1520000Y776000D03*
X1499500Y774000D03*
Y831000D03*
X1510500Y878000D03*
X1510000Y860500D03*
X1512500Y949000D03*
X1508500Y1028500D03*
Y1050500D03*
X1488500Y1096000D03*
X1489096Y1131456D03*
X1489108Y1121674D03*
X1499675Y1142673D03*
X1489333Y1147664D03*
X1480000Y1320000D03*
X1499783Y1369303D03*
X1509783D03*
X1519783D03*
X1479783D03*
X1489783D03*
X1494783D03*
X1484783D03*
X1504783D03*
X1514783D03*
X1565555Y16517D03*
X1568030Y5500D03*
X1565555Y21517D03*
Y26517D03*
Y31517D03*
Y36517D03*
Y41517D03*
X1557000Y64500D03*
X1561500Y62000D03*
X1564000Y57500D03*
X1564555Y52124D03*
X1525336Y149369D03*
X1555925Y162661D03*
X1545383Y164116D03*
X1560000Y140000D03*
X1552225Y183661D03*
X1559625Y172661D03*
X1563925Y195261D03*
X1526031Y207992D03*
Y198543D03*
X1530531Y195492D03*
Y180492D03*
Y245492D03*
X1526031Y217441D03*
X1530142Y238021D03*
X1550925Y266161D03*
X1546925Y299661D03*
X1553425D03*
X1561425D03*
X1562425Y264661D03*
X1530531Y275492D03*
Y265492D03*
X1537531Y314114D03*
X1545000Y455000D03*
X1560000D03*
X1525000D03*
X1545000Y475000D03*
X1560000D03*
Y500000D03*
Y525000D03*
X1552000Y584500D03*
X1566000Y595000D03*
X1537531Y594626D03*
X1552225Y636417D03*
X1559625Y625417D03*
X1555925Y615417D03*
X1530531Y648248D03*
Y633248D03*
Y618248D03*
X1558925Y650017D03*
X1526031Y670197D03*
X1530531Y688248D03*
X1526031Y660748D03*
Y651299D03*
X1550925Y718917D03*
X1562425Y717417D03*
X1530531Y728248D03*
Y718248D03*
Y698248D03*
X1555000Y770000D03*
X1546925Y752417D03*
X1553425D03*
X1561425D03*
X1537531Y766870D03*
X1525000Y878000D03*
X1564500Y931000D03*
X1548500Y933000D03*
X1564000Y949000D03*
X1552500Y1028000D03*
X1557500Y1043500D03*
X1537531Y1047382D03*
X1559625Y1078173D03*
X1555925Y1068173D03*
X1530531Y1071004D03*
X1552225Y1089173D03*
X1526031Y1122953D03*
Y1113504D03*
Y1104055D03*
X1530531Y1101004D03*
Y1086004D03*
X1550925Y1171673D03*
X1552575Y1139700D03*
X1562425Y1170173D03*
X1530531Y1171004D03*
Y1151004D03*
X1528723Y1138918D03*
X1546898Y1204827D03*
X1553425Y1208897D03*
X1561425Y1205173D03*
X1537879Y1219626D03*
X1530531Y1181004D03*
X1549783Y1369303D03*
X1559783D03*
X1569783D03*
X1529783D03*
X1539783D03*
X1524783D03*
X1534783D03*
X1544783D03*
X1554783D03*
X1564783D03*
X1600000Y20000D03*
X1620000D03*
X1580000D03*
X1603030Y5500D03*
X1613030D03*
X1573030D03*
X1583030D03*
X1593030D03*
X1618030D03*
X1608030D03*
X1598030D03*
X1588030D03*
X1578030D03*
X1600000Y60000D03*
X1620000Y40000D03*
X1600000D03*
X1580000D03*
Y60000D03*
X1620000Y100000D03*
X1600000Y80000D03*
X1620000D03*
X1580000D03*
X1620000Y140000D03*
Y120000D03*
X1585757Y134147D03*
X1607000Y199000D03*
X1595500Y258500D03*
X1621100Y240561D03*
X1608000Y256000D03*
X1600000Y340000D03*
X1620000D03*
Y320000D03*
X1600000D03*
X1579500Y331000D03*
X1597245Y516662D03*
X1583030Y517405D03*
X1573000Y565500D03*
X1580000Y780000D03*
X1576500Y928500D03*
X1597221Y969572D03*
X1583180Y969461D03*
X1596000Y990000D03*
X1611500Y1078000D03*
X1593000Y1043500D03*
X1593500Y1185500D03*
X1581500Y1240000D03*
X1600000Y1320000D03*
X1614783Y1369303D03*
X1604783D03*
X1599783D03*
X1609783D03*
X1619783D03*
X1579783D03*
X1589783D03*
X1574783D03*
X1584783D03*
X1594783D03*
X1640000Y20000D03*
X1660000D03*
X1653030Y5500D03*
X1663030D03*
X1623030D03*
X1633030D03*
X1643030D03*
X1668030D03*
X1658030D03*
X1648030D03*
X1638030D03*
X1628030D03*
X1640000Y60000D03*
X1660000D03*
Y40000D03*
X1640000D03*
Y100000D03*
X1660000D03*
X1640000Y80000D03*
X1660000D03*
Y120000D03*
X1640000D03*
X1661744Y141870D03*
X1650244Y207992D03*
Y198543D03*
X1654744Y195492D03*
Y180492D03*
Y165492D03*
Y245492D03*
X1650244Y217441D03*
X1654744Y235492D03*
X1652387Y277343D03*
X1653789Y267766D03*
X1639000Y320000D03*
X1640000Y340000D03*
X1660000D03*
X1661744Y314114D03*
X1660000Y400000D03*
X1640000Y360000D03*
X1660000Y440000D03*
Y480000D03*
X1640000D03*
Y460000D03*
X1660000D03*
X1640000Y500000D03*
X1660000D03*
Y520000D03*
X1640000D03*
X1660000Y540000D03*
X1640000D03*
Y560000D03*
X1660000D03*
X1661744Y594626D03*
X1654744Y648248D03*
Y633248D03*
Y618248D03*
X1623888Y689917D03*
X1652962Y670204D03*
X1654744Y688248D03*
X1650244Y660748D03*
Y651299D03*
X1637000Y729000D03*
X1638000Y740000D03*
X1654744Y728248D03*
Y718248D03*
Y698248D03*
X1630000Y780000D03*
Y760000D03*
X1661744Y766870D03*
X1625000Y800000D03*
X1651500Y913500D03*
X1650000Y950000D03*
Y980000D03*
X1653500Y1016500D03*
X1650000Y1000000D03*
X1632000Y1049500D03*
X1654744Y1071004D03*
X1661744Y1047382D03*
X1650244Y1122953D03*
Y1113504D03*
Y1104055D03*
X1654744Y1101004D03*
Y1086004D03*
X1627563Y1132075D03*
X1627802Y1118949D03*
X1627769Y1110037D03*
X1635688Y1141158D03*
X1650841Y1168660D03*
X1654744Y1151004D03*
Y1141004D03*
X1627197Y1143044D03*
X1661744Y1219626D03*
X1668378Y1181004D03*
X1640000Y1260000D03*
X1660000D03*
X1640000Y1320000D03*
Y1300000D03*
X1660000Y1320000D03*
Y1300000D03*
Y1280000D03*
X1640000D03*
X1664783Y1369303D03*
X1654783D03*
X1644783D03*
X1634783D03*
X1624783D03*
X1649783D03*
X1659783D03*
X1629783D03*
X1639783D03*
X1700000Y20000D03*
X1680000D03*
X1703030Y5500D03*
X1713030D03*
X1673030D03*
X1683030D03*
X1693030D03*
X1718030D03*
X1708030D03*
X1698030D03*
X1688030D03*
X1678030D03*
X1700000Y60000D03*
Y40000D03*
X1680000Y60000D03*
Y40000D03*
Y100000D03*
Y80000D03*
X1700000Y100000D03*
Y80000D03*
Y140000D03*
Y120000D03*
X1680000D03*
X1679500Y144000D03*
X1680138Y162661D03*
X1676438Y183661D03*
X1683838Y172661D03*
X1688138Y195261D03*
X1675475Y267424D03*
X1671138Y299661D03*
X1677638D03*
X1685638D03*
X1686638Y264661D03*
X1678500Y320000D03*
X1700000Y400000D03*
X1680000Y380000D03*
X1700000Y360000D03*
X1680000Y440000D03*
Y420000D03*
X1700000Y440000D03*
Y420000D03*
Y460000D03*
X1680000Y480000D03*
Y460000D03*
Y500000D03*
Y520000D03*
X1700000Y540000D03*
X1680000D03*
X1707495Y517152D03*
X1700000Y560000D03*
X1680000D03*
X1676438Y636417D03*
X1683838Y625417D03*
X1680138Y615417D03*
X1688138Y648017D03*
X1675138Y718917D03*
X1686638Y717417D03*
X1710000Y770000D03*
Y785000D03*
X1685000Y770000D03*
X1671138Y752417D03*
X1677638D03*
X1685638D03*
X1709000Y915000D03*
X1687000Y905500D03*
X1716500Y943500D03*
X1706000Y1022000D03*
X1683838Y1078173D03*
X1680138Y1068173D03*
X1688138Y1100773D03*
X1676438Y1089173D03*
X1686638Y1170173D03*
X1675138Y1171673D03*
X1685638Y1205173D03*
X1677638D03*
X1671138D03*
X1680000Y1240000D03*
X1700000Y1260000D03*
X1680000D03*
X1700000Y1320000D03*
Y1300000D03*
Y1280000D03*
X1680000Y1320000D03*
Y1300000D03*
Y1280000D03*
X1714783Y1369303D03*
X1704783D03*
X1694783D03*
X1684783D03*
X1674783D03*
X1699783D03*
X1709783D03*
X1669783D03*
X1679783D03*
X1689783D03*
X1760000Y20000D03*
X1740000D03*
X1720000D03*
X1753030Y5500D03*
X1763030D03*
X1723030D03*
X1733030D03*
X1743030D03*
X1758030D03*
X1748030D03*
X1738030D03*
X1728030D03*
X1760000Y60000D03*
Y40000D03*
X1740000D03*
Y60000D03*
X1720000Y40000D03*
Y60000D03*
X1740000Y100000D03*
X1760000D03*
X1740000Y80000D03*
X1760000D03*
X1720000Y100000D03*
Y80000D03*
X1740000Y140000D03*
X1760000Y120000D03*
X1740000D03*
X1720000Y140000D03*
Y120000D03*
X1728500Y249500D03*
X1746600Y240561D03*
X1760486Y217441D03*
X1763500Y288000D03*
X1720000Y300000D03*
Y280000D03*
Y340000D03*
X1760000D03*
X1740000Y320000D03*
X1760000Y440000D03*
Y420000D03*
Y500000D03*
Y480000D03*
Y460000D03*
X1740000Y540000D03*
X1760000D03*
Y520000D03*
X1721710Y516409D03*
X1745000Y670000D03*
Y690000D03*
Y660000D03*
X1730000Y690000D03*
Y670000D03*
Y730000D03*
Y710000D03*
X1735000Y785000D03*
X1730000Y775000D03*
Y750000D03*
X1725000Y800000D03*
X1718000Y876000D03*
X1759884Y969161D03*
X1742001Y965464D03*
X1755000Y1045000D03*
X1725000D03*
X1745000Y1100000D03*
X1759055Y1113504D03*
X1736725Y1123446D03*
X1748100Y1142673D03*
X1736871Y1158178D03*
X1736941Y1141871D03*
X1728000Y1204500D03*
X1720000Y1320000D03*
X1760000D03*
X1753000Y1302000D03*
X1764783Y1369303D03*
X1754783D03*
X1744783D03*
X1734783D03*
X1724783D03*
X1749783D03*
X1759783D03*
X1719783D03*
X1729783D03*
X1739783D03*
X1778030Y5500D03*
X1793030D03*
X1803030D03*
X1813030D03*
X1808030D03*
X1798030D03*
X1783030D03*
X1788030D03*
X1773030D03*
X1768030D03*
X1780000Y60000D03*
Y40000D03*
X1800000Y100000D03*
Y80000D03*
X1780000Y100000D03*
Y80000D03*
X1800000Y120000D03*
X1780000D03*
X1785956Y141870D03*
X1804350Y162661D03*
X1801988Y183904D03*
X1808050Y172661D03*
X1812350Y195261D03*
X1774456Y207992D03*
Y198543D03*
X1778956Y195492D03*
Y180492D03*
X1775140Y165728D03*
X1778956Y245492D03*
Y235492D03*
X1799350Y266161D03*
X1795350Y299661D03*
X1801850D03*
X1809850D03*
X1810850Y264661D03*
X1778956Y275492D03*
Y265492D03*
X1785956Y314114D03*
X1800000Y440000D03*
X1780000D03*
X1800000Y500000D03*
X1780000D03*
X1800000Y480000D03*
Y460000D03*
X1780000Y480000D03*
Y460000D03*
X1800000Y540000D03*
X1780000D03*
X1800000Y520000D03*
X1780000D03*
X1800000Y560000D03*
X1785956Y594626D03*
X1800650Y636417D03*
X1808050Y625417D03*
X1804350Y615417D03*
X1812350Y648017D03*
X1778956Y648248D03*
Y633248D03*
Y618248D03*
X1774456Y670197D03*
X1778956Y688248D03*
X1774456Y660748D03*
Y651299D03*
X1799326Y717506D03*
X1811474Y717423D03*
X1778956Y728248D03*
Y718248D03*
Y698248D03*
X1766721Y716500D03*
X1795468Y752594D03*
X1801968D03*
X1809968D03*
X1785956Y766870D03*
X1773500Y879500D03*
X1771000Y944500D03*
X1799000Y945500D03*
X1788361Y964676D03*
X1799051Y963346D03*
X1785956Y1047382D03*
X1808050Y1078173D03*
X1800750Y1067973D03*
X1778956Y1071004D03*
X1800650Y1089173D03*
X1811968Y1100773D03*
X1774456Y1122953D03*
Y1104055D03*
X1778956Y1101004D03*
Y1086004D03*
X1799350Y1171673D03*
X1810850Y1170173D03*
X1778956Y1171004D03*
Y1151004D03*
Y1141004D03*
X1795350Y1205173D03*
X1801850D03*
X1809850D03*
X1785956Y1219626D03*
X1778956Y1181004D03*
X1772111Y1232695D03*
X1804783Y1369303D03*
X1794783D03*
X1784783D03*
X1774783D03*
X1799783D03*
X1809783D03*
X1769783D03*
X1779783D03*
X1789783D03*
X1843030Y5500D03*
X1853030D03*
X1863030D03*
X1838030D03*
X1858030D03*
X1848030D03*
X1823030D03*
X1833030D03*
X1828030D03*
X1818030D03*
X1860000Y60000D03*
Y80000D03*
Y100000D03*
X1840000D03*
X1820000D03*
X1860000Y140000D03*
Y120000D03*
X1840000D03*
X1820000Y140000D03*
Y120000D03*
X1856219Y212661D03*
X1841169Y254661D03*
X1840000Y340000D03*
Y320000D03*
X1860000D03*
X1820000D03*
Y440000D03*
Y480000D03*
Y460000D03*
X1840000Y540000D03*
X1820000D03*
X1845545Y516536D03*
X1831330Y517279D03*
X1840000Y580000D03*
X1820000D03*
X1840000Y560000D03*
X1820000D03*
X1862200Y686700D03*
X1856219Y665417D03*
X1850000Y745000D03*
X1837576Y707417D03*
X1820000Y780000D03*
X1857363Y1002625D03*
X1845363D03*
X1849363D03*
X1861363D03*
X1853363D03*
X1856437Y1106400D03*
X1850532Y1153286D03*
X1836231Y1140669D03*
X1860000Y1320000D03*
X1854783Y1369303D03*
X1844783D03*
X1834783D03*
X1824783D03*
X1814783D03*
X1849783D03*
X1859783D03*
X1819783D03*
X1829783D03*
X1839783D03*
X1878030Y5500D03*
X1883030D03*
X1873030D03*
X1868030D03*
X1909030D03*
X1888030D03*
X1880000Y60000D03*
X1900000D03*
X1880000Y80000D03*
X1900000D03*
Y100000D03*
X1880000D03*
X1900000Y120000D03*
X1880000Y140000D03*
Y120000D03*
X1910169Y141870D03*
X1898669Y207992D03*
Y198543D03*
X1903169Y195492D03*
Y180492D03*
Y165492D03*
X1885204Y184345D03*
X1873500Y219000D03*
X1865169Y247161D03*
Y234661D03*
X1903169Y245492D03*
X1898669Y217441D03*
X1903169Y235492D03*
X1881088Y296184D03*
X1903169Y275492D03*
Y265492D03*
X1880969Y276861D03*
X1880000Y340000D03*
Y320000D03*
X1910169Y314114D03*
X1890000Y400000D03*
Y380000D03*
Y360000D03*
Y440000D03*
Y420000D03*
X1910169Y594626D03*
X1903169Y648248D03*
Y633248D03*
Y618248D03*
X1885300Y636800D03*
X1898669Y670197D03*
X1903169Y688248D03*
X1898669Y660748D03*
Y651299D03*
X1903169Y728248D03*
Y718248D03*
Y698248D03*
X1880969Y729617D03*
X1865169Y699917D03*
X1880000Y780000D03*
X1910169Y766870D03*
X1887169Y752917D03*
X1892443Y894350D03*
X1884200Y895000D03*
X1865363Y1002625D03*
X1868100Y1055410D03*
X1903169Y1071004D03*
X1910169Y1047382D03*
X1898669Y1122953D03*
Y1113504D03*
Y1104055D03*
X1903169Y1101004D03*
Y1086004D03*
X1863131Y1133108D03*
X1903169Y1171004D03*
X1903100Y1149700D03*
X1903169Y1141004D03*
X1864352Y1153308D03*
X1871174Y1138730D03*
X1887169Y1205673D03*
X1910169Y1219626D03*
X1903169Y1181004D03*
X1880969Y1182373D03*
X1900000Y1260000D03*
Y1280000D03*
Y1320000D03*
Y1300000D03*
X1904783Y1369303D03*
X1894783D03*
X1884783D03*
X1874783D03*
X1864783D03*
X1899783D03*
X1909783D03*
X1869783D03*
X1879783D03*
X1889783D03*
X1929343Y16525D03*
Y11525D03*
Y6525D03*
X1914030Y5500D03*
X1919030D03*
X1924030D03*
X1920000Y60000D03*
X1929343Y46525D03*
Y41525D03*
Y36525D03*
Y31525D03*
Y26525D03*
Y21525D03*
Y66525D03*
Y61525D03*
Y56525D03*
Y51525D03*
X1920000Y80000D03*
Y100000D03*
X1929343Y116525D03*
Y111525D03*
Y106525D03*
Y101525D03*
Y96525D03*
Y91525D03*
Y86525D03*
Y81525D03*
Y76525D03*
Y71525D03*
X1920000Y120000D03*
X1929343Y121525D03*
Y126525D03*
Y136525D03*
Y146525D03*
Y156525D03*
Y161525D03*
Y151525D03*
Y141525D03*
Y131525D03*
Y176525D03*
Y186525D03*
Y196525D03*
Y206525D03*
Y166525D03*
Y211525D03*
Y201525D03*
Y191525D03*
Y181525D03*
Y171525D03*
Y226525D03*
Y236525D03*
Y246525D03*
Y256525D03*
Y216525D03*
Y261525D03*
Y251525D03*
Y241525D03*
Y231525D03*
Y221525D03*
Y276525D03*
Y286525D03*
Y296525D03*
Y306525D03*
Y266525D03*
Y301525D03*
Y291525D03*
Y281525D03*
Y271525D03*
Y326525D03*
Y336525D03*
Y346525D03*
Y356525D03*
Y316525D03*
Y351525D03*
Y341525D03*
Y331525D03*
Y321525D03*
Y311525D03*
Y376525D03*
Y386525D03*
Y396525D03*
Y406525D03*
Y366525D03*
Y401525D03*
Y391525D03*
Y381525D03*
Y371525D03*
Y361525D03*
Y426525D03*
Y436525D03*
Y446525D03*
Y416525D03*
Y451525D03*
Y441525D03*
Y431525D03*
Y421525D03*
Y411525D03*
Y476525D03*
Y486525D03*
Y496525D03*
Y456525D03*
Y466525D03*
Y501525D03*
Y491525D03*
Y481525D03*
Y471525D03*
Y461525D03*
Y526525D03*
Y536525D03*
Y546525D03*
Y506525D03*
Y516525D03*
Y551525D03*
Y541525D03*
Y531525D03*
Y521525D03*
Y511525D03*
Y576525D03*
Y586525D03*
Y596525D03*
Y556525D03*
Y566525D03*
Y591525D03*
Y581525D03*
Y571525D03*
Y561525D03*
Y626525D03*
Y636525D03*
Y646525D03*
Y606525D03*
Y616525D03*
Y641525D03*
Y631525D03*
Y621525D03*
Y611525D03*
Y601525D03*
Y676525D03*
Y686525D03*
Y696525D03*
Y656525D03*
Y666525D03*
Y691525D03*
Y681525D03*
Y671525D03*
Y661525D03*
Y651525D03*
Y726525D03*
Y736525D03*
Y706525D03*
Y716525D03*
Y741525D03*
Y731525D03*
Y721525D03*
Y711525D03*
Y701525D03*
Y776525D03*
Y786525D03*
Y746525D03*
Y756525D03*
Y766525D03*
Y791525D03*
Y781525D03*
Y771525D03*
Y761525D03*
Y751525D03*
Y826525D03*
Y836525D03*
Y796525D03*
Y806525D03*
Y816525D03*
Y841525D03*
Y831525D03*
Y821525D03*
Y811525D03*
Y801525D03*
Y876525D03*
Y886525D03*
Y846525D03*
Y856525D03*
Y866525D03*
Y881525D03*
Y871525D03*
Y861525D03*
Y851525D03*
Y926525D03*
Y896525D03*
Y906525D03*
Y916525D03*
Y931525D03*
Y921525D03*
Y911525D03*
Y901525D03*
Y891525D03*
Y936525D03*
Y973863D03*
Y978863D03*
Y983863D03*
Y951525D03*
Y956525D03*
Y961525D03*
Y966525D03*
Y946525D03*
Y941525D03*
Y988863D03*
Y993863D03*
Y998863D03*
Y1003863D03*
Y1008863D03*
Y1033863D03*
Y1028863D03*
Y1023863D03*
Y1018863D03*
Y1013863D03*
Y1073863D03*
Y1083863D03*
Y1043863D03*
Y1053863D03*
Y1063863D03*
Y1078863D03*
Y1068863D03*
Y1058863D03*
Y1048863D03*
Y1038863D03*
Y1123863D03*
Y1093863D03*
Y1103863D03*
Y1113863D03*
Y1128863D03*
Y1118863D03*
Y1108863D03*
Y1098863D03*
Y1088863D03*
Y1173863D03*
Y1133863D03*
Y1143863D03*
Y1153863D03*
Y1163863D03*
Y1178863D03*
Y1168863D03*
Y1158863D03*
Y1148863D03*
Y1138863D03*
Y1223863D03*
Y1183863D03*
Y1193863D03*
Y1203863D03*
Y1213863D03*
Y1228863D03*
Y1218863D03*
Y1208863D03*
Y1198863D03*
Y1188863D03*
X1920000Y1260000D03*
X1929343Y1273863D03*
Y1233863D03*
Y1243863D03*
Y1253863D03*
Y1263863D03*
Y1268863D03*
Y1258863D03*
Y1248863D03*
Y1238863D03*
X1920000Y1280000D03*
Y1320000D03*
Y1300000D03*
X1929343Y1323863D03*
Y1283863D03*
Y1293863D03*
Y1303863D03*
Y1313863D03*
Y1318863D03*
Y1308863D03*
Y1298863D03*
Y1288863D03*
Y1278863D03*
Y1333863D03*
Y1343863D03*
Y1353863D03*
X1924783Y1369303D03*
X1914783D03*
X1919783D03*
X1929343Y1358863D03*
Y1348863D03*
Y1338863D03*
Y1328863D03*
Y1363863D03*
G54D28*
X188706Y941328D03*
X194206D03*
X260703Y529168D03*
X255203D03*
X702483Y945989D03*
X730882Y888502D03*
X716233Y868219D03*
X733422Y857828D03*
X721552Y951317D03*
X725852Y951067D03*
X763883Y907689D03*
X755883D03*
X750883Y903689D03*
X802102Y51075D03*
X799102Y48575D03*
X802102Y46075D03*
X799102Y43575D03*
X802102Y41075D03*
X868100Y685600D03*
X871700D03*
X875300D03*
X884600Y688800D03*
X881000D03*
X877400D03*
X891000Y743500D03*
X870500Y762500D03*
X932294Y1379995D03*
X928194D03*
X1843731Y936066D03*
X1843811Y940067D03*
X1830665Y941751D03*
X1836165D03*
X1908107Y831894D03*
X1902607D03*
X1907999Y846368D03*
X1902499D03*
G54D23*
X111800Y987200D03*
Y983200D03*
X115800Y979200D03*
X119800Y971200D03*
Y975200D03*
Y979200D03*
X115800Y975200D03*
X119800Y987200D03*
Y983200D03*
X115800Y971200D03*
Y983200D03*
Y987200D03*
X119163Y959625D03*
X121914Y1003491D03*
X153263Y568725D03*
X146263D03*
X144263Y573225D03*
X138763Y568725D03*
X148763Y576225D03*
X188614Y591491D03*
X182500Y559200D03*
Y571200D03*
Y575200D03*
X178500D03*
Y571200D03*
X182500Y567200D03*
X186500Y559200D03*
Y563200D03*
Y567200D03*
X182500Y563200D03*
X186500Y575200D03*
Y571200D03*
X184017Y951112D03*
Y945612D03*
X198463Y945525D03*
Y951025D03*
X265392Y539225D03*
Y533725D03*
X250586Y533920D03*
Y539420D03*
X465346Y1122953D03*
X858632Y399200D03*
X855032D03*
Y395600D03*
X858632D03*
X855032Y392000D03*
X858632D03*
X852832Y406400D03*
Y402800D03*
X856432Y406400D03*
Y402800D03*
X852832Y410000D03*
X856432D03*
X1398493Y314114D03*
X1717681Y1006054D03*
X1712181Y1001554D03*
X1757600Y987200D03*
X1761600D03*
Y983200D03*
X1757600D03*
X1761600Y991200D03*
Y999200D03*
Y995200D03*
X1757600Y991200D03*
X1753600Y995200D03*
Y999200D03*
X1757600D03*
Y995200D03*
X1726681Y1001554D03*
X1719681D03*
X1722181Y1009054D03*
X1763714Y1015491D03*
X1840419Y945557D03*
Y951057D03*
X1825945Y945449D03*
Y950949D03*
G54D36*
X944882Y-63877D03*
G54D38*
X942126Y58465D03*
Y346457D03*
Y437598D03*
Y725590D03*
X1110236Y58465D03*
Y346457D03*
Y437598D03*
Y725590D03*
G54D33*
X496653Y80906D03*
X1465157D03*
G54D15*
X60540Y-85109D03*
X59536Y1573374D03*
X79000Y1301900D03*
X1826700Y77600D03*
X1865705Y1573374D03*
X1898432Y-93682D03*
X1908500Y1346800D03*
G54D12*
X15157Y474409D03*
X904921Y-25591D03*
X1894684Y474409D03*
G54D18*
X80019Y51968D03*
X127263Y20472D03*
X631200Y51968D03*
X678444Y20472D03*
X1250689Y51969D03*
X1297933Y20472D03*
X1801870Y51969D03*
X1849114Y20472D03*
G54D10*
X15157Y21653D03*
X904921Y564960D03*
X1894685Y21654D03*
G54D34*
X496653Y110552D03*
X1465157D03*
G54D26*
X173228Y1062992D03*
X421653Y1141732D03*
X670079Y1062992D03*
X1343701D03*
X1592126Y1141732D03*
X1840551Y1062992D03*
G54D35*
X503248Y829921D03*
X1673917D03*
G54D13*
X31496Y882677D03*
X168307Y646457D03*
X660236D03*
X718110Y820866D03*
X1366142Y646457D03*
X1462992Y866929D03*
X1602756Y646457D03*
X1903346Y803937D03*
G54D39*
X975787Y-25590D03*
G54D17*
X103642Y36220D03*
X654822D03*
X1274311D03*
X1825492D03*
G54D27*
X173228Y1114173D03*
X670079D03*
X1343700D03*
X1840551D03*
G54D40*
X975786Y564960D03*
G54D44*
X1104527Y1630792D03*
G54D16*
X47000Y1107500D03*
X549279Y513331D03*
X525579Y538331D03*
X557279Y513331D03*
X533879Y566031D03*
X548767Y556819D03*
X520579Y553231D03*
X517499Y576931D03*
X575700Y528831D03*
X563279Y506731D03*
X704399Y626799D03*
Y618399D03*
Y622599D03*
X748500Y1287500D03*
X752000Y1197500D03*
X756000Y1225500D03*
X770000Y1231500D03*
X769500Y1283500D03*
X827000Y1168000D03*
X802500Y1194500D03*
X807500D03*
X812500D03*
X810000Y1191500D03*
X805000D03*
X870163Y836153D03*
X865663Y834403D03*
X895869Y932822D03*
X898920Y1020000D03*
X906000Y1222000D03*
X924500Y1236000D03*
X932500Y1493200D03*
X926500Y1499700D03*
X918500D03*
X906000Y1543700D03*
X962900Y905000D03*
X953967Y933635D03*
X948942Y974655D03*
X961134Y976191D03*
X946138Y1006299D03*
X944921Y1515200D03*
X986614Y1619764D03*
X974016D03*
Y1597126D03*
X986614D03*
X974016Y1591220D03*
Y1603031D03*
Y1613858D03*
X986614Y1591220D03*
Y1613858D03*
Y1603031D03*
X974016Y1625669D03*
X986614D03*
X1031563Y852453D03*
X1025774Y1001538D03*
X992994Y1005740D03*
X1037000Y1067100D03*
X1032500D03*
X1017000Y1093950D03*
X1021200Y1094300D03*
X1002362Y1597126D03*
X1014961D03*
X1030709D03*
X1002362Y1591220D03*
Y1603031D03*
X1014961Y1591220D03*
Y1603031D03*
X1030709Y1591220D03*
Y1603031D03*
X1076000Y-10500D03*
X1062854Y83434D03*
X1053200Y901703D03*
X1043882Y901568D03*
X1082500Y1067100D03*
X1073500D03*
X1064500Y1096150D03*
X1068700Y1096600D03*
X1066750Y1224035D03*
X1079250D03*
X1066750Y1209862D03*
X1079250D03*
X1066750Y1216949D03*
X1079250D03*
X1066750Y1231122D03*
X1079250D03*
X1066750Y1238209D03*
X1079250D03*
X1066750Y1245295D03*
X1079250D03*
X1066750Y1301988D03*
X1079250D03*
X1066750Y1309075D03*
X1079250D03*
X1066750Y1316161D03*
X1079250D03*
X1066750Y1323248D03*
X1079250D03*
X1066750Y1294902D03*
X1079250D03*
X1066750Y1330335D03*
X1079250D03*
X1066750Y1387028D03*
X1079250D03*
X1066750Y1394114D03*
X1079250D03*
X1066750Y1401201D03*
X1079250D03*
X1066750Y1408287D03*
X1079250D03*
X1066750Y1415374D03*
X1079250D03*
X1066750Y1379941D03*
X1079250D03*
X1043307Y1597126D03*
Y1591220D03*
Y1603031D03*
X1100847Y905617D03*
X1105847D03*
X1110847D03*
X1108347Y902617D03*
X1103347D03*
X1119700Y1067200D03*
X1124500D03*
X1101580Y1091120D03*
X1107100Y1096050D03*
X1111600Y1097800D03*
X1090818Y1531620D03*
X1092927Y1558887D03*
Y1555087D03*
X1095938Y1531620D03*
Y1535420D03*
X1090818D03*
X1096547Y1558887D03*
Y1555087D03*
X1265250Y167823D03*
X1252750D03*
X1376963D03*
X1355700Y587600D03*
X1359700D03*
X1389463Y167823D03*
G54D25*
X127988Y194242D03*
Y181742D03*
Y634498D03*
Y646998D03*
Y1087254D03*
Y1099754D03*
X252200Y194242D03*
Y181742D03*
Y634498D03*
Y646998D03*
Y1087254D03*
Y1099754D03*
X322545Y72845D03*
X376413Y194242D03*
Y181742D03*
Y634498D03*
Y646998D03*
Y1087254D03*
Y1099754D03*
X453473Y1089300D03*
X500625Y194242D03*
Y181742D03*
Y634498D03*
Y646998D03*
X460673Y1071976D03*
X460873Y1077526D03*
X500625Y1087254D03*
Y1099754D03*
X624838Y194242D03*
Y181742D03*
Y634498D03*
Y646998D03*
Y1087254D03*
Y1099754D03*
X696787Y580633D03*
X749051Y194242D03*
Y181742D03*
Y634498D03*
Y646998D03*
X708683Y876958D03*
X749051Y1087254D03*
Y1099754D03*
X928600Y-115200D03*
X986713Y-115570D03*
X971713D03*
X1046713D03*
X1076713D03*
X1117535Y-115157D03*
X1091089Y988592D03*
X1105262D03*
X1119435D03*
X1133609D03*
X1095026Y995678D03*
X1109199D03*
X1123372D03*
X1091089Y1002765D03*
X1105262D03*
X1119435D03*
X1133609D03*
X1095026Y1009852D03*
X1109199D03*
X1123372D03*
X1091089Y1016938D03*
X1105262D03*
X1119435D03*
X1133609D03*
X1095026Y1024025D03*
X1109199D03*
X1123372D03*
X1091089Y1031111D03*
X1105262D03*
X1119435D03*
X1133609D03*
X1095026Y1038198D03*
X1109199D03*
X1123372D03*
X1091089Y1160257D03*
Y1174430D03*
X1105262Y1160257D03*
Y1174430D03*
X1119435Y1160257D03*
Y1174430D03*
X1133609Y1160257D03*
Y1174430D03*
X1095026Y1167343D03*
X1109199D03*
X1123372D03*
X1091089Y1188603D03*
Y1202776D03*
Y1216949D03*
X1105262Y1188603D03*
Y1202776D03*
Y1216949D03*
X1119435Y1188603D03*
Y1202776D03*
Y1216949D03*
X1133609Y1188603D03*
Y1202776D03*
Y1216949D03*
X1095026Y1181516D03*
Y1195690D03*
Y1209863D03*
Y1224036D03*
X1109199Y1181516D03*
Y1195690D03*
Y1209863D03*
Y1224036D03*
X1123372Y1181516D03*
Y1195690D03*
Y1209863D03*
Y1224036D03*
X1091089Y1231123D03*
Y1245296D03*
Y1259469D03*
Y1273642D03*
X1105262Y1231123D03*
Y1245296D03*
Y1259469D03*
Y1273642D03*
X1119435Y1231123D03*
Y1245296D03*
Y1259469D03*
Y1273642D03*
X1133609Y1231123D03*
Y1245296D03*
Y1259469D03*
Y1273642D03*
X1095026Y1238209D03*
Y1252382D03*
Y1266556D03*
X1109199Y1238209D03*
Y1252382D03*
Y1266556D03*
X1123372Y1238209D03*
Y1252382D03*
Y1266556D03*
X1091089Y1287816D03*
Y1301989D03*
Y1316162D03*
X1105262Y1287816D03*
Y1301989D03*
Y1316162D03*
X1119435Y1287816D03*
Y1301989D03*
Y1316162D03*
X1133609Y1287816D03*
Y1301989D03*
Y1316162D03*
X1095026Y1280729D03*
Y1294902D03*
Y1309075D03*
Y1323249D03*
X1109199Y1280729D03*
Y1294902D03*
Y1309075D03*
Y1323249D03*
X1123372Y1280729D03*
Y1294902D03*
Y1309075D03*
Y1323249D03*
X1091089Y1330335D03*
Y1344508D03*
Y1358682D03*
Y1372855D03*
X1105262Y1330335D03*
Y1344508D03*
Y1358682D03*
Y1372855D03*
X1119435Y1330335D03*
Y1344508D03*
Y1358682D03*
Y1372855D03*
X1133609Y1330335D03*
Y1344508D03*
Y1358682D03*
Y1372855D03*
X1095026Y1337422D03*
Y1351595D03*
Y1365768D03*
X1109199Y1337422D03*
Y1351595D03*
Y1365768D03*
X1123372Y1337422D03*
Y1351595D03*
Y1365768D03*
X1091089Y1387028D03*
Y1401201D03*
X1105262Y1387028D03*
Y1401201D03*
X1119435Y1387028D03*
Y1401201D03*
X1133609Y1387028D03*
Y1401201D03*
X1095026Y1379942D03*
Y1394115D03*
Y1408288D03*
X1109199Y1379942D03*
Y1394115D03*
Y1408288D03*
X1123372Y1379942D03*
Y1394115D03*
Y1408288D03*
X1101457Y1588583D03*
X1119685D03*
X1108150D03*
X1126378D03*
X1182590Y254388D03*
X1174037Y281343D03*
X1278500Y634498D03*
Y646998D03*
Y1087254D03*
Y1099754D03*
X1402713Y181742D03*
Y194242D03*
Y634498D03*
Y646998D03*
Y1087254D03*
Y1099754D03*
X1526925Y181742D03*
Y194242D03*
Y634498D03*
Y646998D03*
Y1087254D03*
Y1099754D03*
X1651138Y181742D03*
Y194242D03*
Y634498D03*
Y646998D03*
Y1087254D03*
Y1099754D03*
X1725350Y634498D03*
Y646998D03*
X1775350Y181742D03*
Y194242D03*
Y1087254D03*
Y1099754D03*
X1859017Y161725D03*
X1859117Y167375D03*
X1851717Y179075D03*
X1858917Y614481D03*
X1859117Y620131D03*
X1851717Y635331D03*
X1848491Y819787D03*
Y823787D03*
Y815787D03*
Y807787D03*
Y811787D03*
X1899563Y181742D03*
Y194242D03*
Y634498D03*
Y646998D03*
X1871000Y1073300D03*
X1899563Y1087254D03*
Y1099754D03*
X1863700Y1085000D03*
G54D29*
X184295Y1009469D03*
Y1014969D03*
X198741Y1014882D03*
Y1009382D03*
X265275Y596896D03*
X250974Y597308D03*
X265275Y602396D03*
X250974Y602808D03*
X429724Y63977D03*
X443898D03*
X458071D03*
X436811Y67914D03*
X450984D03*
X429724Y92323D03*
Y106496D03*
Y78150D03*
X436811Y82087D03*
X450984D03*
X443898Y92323D03*
X458071D03*
X436811Y96260D03*
X450984D03*
X443898Y106496D03*
X458071D03*
X436811Y110433D03*
X450984D03*
X443898Y78150D03*
X458071D03*
X429724Y120670D03*
X443898D03*
X458071D03*
X465157Y67914D03*
X472244Y63977D03*
X479331Y67914D03*
X465157Y82087D03*
Y96260D03*
Y110433D03*
X479331Y82087D03*
X472244Y92323D03*
X479331Y96260D03*
X472244Y106496D03*
X479331Y110433D03*
X472244Y78150D03*
Y120670D03*
X514764Y63977D03*
X550197Y67914D03*
X536024D03*
X521850D03*
X543110Y63977D03*
X528937D03*
X557283D03*
X514764Y106496D03*
Y92323D03*
Y78150D03*
X550197Y110433D03*
X536024D03*
X521850D03*
X543110Y106496D03*
X528937D03*
X550197Y96260D03*
X536024D03*
X521850D03*
X543110Y92323D03*
X528937D03*
X550197Y82087D03*
X536024D03*
X521850D03*
X543110Y78150D03*
X528937D03*
X557283Y106496D03*
Y92323D03*
Y78150D03*
X514764Y120670D03*
X543110D03*
X528937D03*
X557283D03*
X564370Y67914D03*
Y110433D03*
Y96260D03*
Y82087D03*
X1398228Y63977D03*
X1412402D03*
X1426575D03*
X1405315Y67914D03*
X1419488D03*
X1398228Y92323D03*
Y106496D03*
Y78150D03*
X1405315Y82087D03*
X1419488D03*
X1412402Y92323D03*
X1426575D03*
X1405315Y96260D03*
X1419488D03*
X1412402Y106496D03*
X1426575D03*
X1405315Y110433D03*
X1419488D03*
X1412402Y78150D03*
X1426575D03*
X1398228Y120670D03*
X1412402D03*
X1426575D03*
X1433661Y67914D03*
X1440748Y63977D03*
X1447835Y67914D03*
X1433661Y82087D03*
Y96260D03*
Y110433D03*
X1447835Y82087D03*
X1440748Y92323D03*
X1447835Y96260D03*
X1440748Y106496D03*
X1447835Y110433D03*
X1440748Y78150D03*
Y120670D03*
X1483268Y63977D03*
X1518701Y67914D03*
X1504528D03*
X1490354D03*
X1511614Y63977D03*
X1497441D03*
X1483268Y106496D03*
Y92323D03*
Y78150D03*
X1518701Y110433D03*
X1504528D03*
X1490354D03*
X1511614Y106496D03*
X1497441D03*
X1518701Y96260D03*
X1504528D03*
X1490354D03*
X1511614Y92323D03*
X1497441D03*
X1518701Y82087D03*
X1504528D03*
X1490354D03*
X1511614Y78150D03*
X1497441D03*
X1483268Y120670D03*
X1511614D03*
X1497441D03*
X1532874Y67914D03*
X1525787Y63977D03*
X1532874Y110433D03*
X1525787Y106496D03*
X1532874Y96260D03*
X1525787Y92323D03*
X1532874Y82087D03*
X1525787Y78150D03*
Y120670D03*
X1825971Y1015512D03*
Y1010012D03*
X1840445Y1015620D03*
Y1010120D03*
X1912551Y836444D03*
Y841944D03*
G54D30*
X188552Y1019166D03*
X194052D03*
X255410Y607833D03*
X260910D03*
X1850151Y835119D03*
X1850177Y838746D03*
X1838239Y831626D03*
X1845579Y831731D03*
X1838311Y827911D03*
X1845651Y828016D03*
X1860276Y916059D03*
Y912059D03*
X1835895Y1020064D03*
X1830395D03*
X1872276Y916059D03*
X1876276D03*
Y920059D03*
X1872276D03*
X1868276Y916059D03*
X1864276Y912059D03*
X1868276D03*
X1864276Y916059D03*
X1876276Y912059D03*
X1872276D03*
X1875801Y946796D03*
X1875769Y951122D03*
X1880122Y954062D03*
X1880383Y950341D03*
G36*
G01X149668Y380135D02*
G02X112735I-18466J-14781D01*
G03X119308Y392599I-29176J23351D01*
G02X143095I11894J-3623D01*
G03X149668Y380135I35749J10887D01*
G37*
G36*
G01X149667Y832891D02*
G02X112734I-18466J-14781D01*
G03X119307Y845355I-29176J23351D01*
G02X143094I11894J-3623D01*
G03X149667Y832891I35749J10887D01*
G37*
G36*
G01X149668Y1285647D02*
G02X112735I-18466J-14781D01*
G03X119308Y1298111I-29176J23351D01*
G02X143095I11894J-3623D01*
G03X149668Y1285647I35749J10887D01*
G37*
G36*
G01X397699Y380135D02*
G02X360766I-18467J-14781D01*
G03X367339Y392599I-29176J23351D01*
G02X391126I11894J-3623D01*
G03X397699Y380135I35749J10887D01*
G37*
G36*
G01Y832891D02*
G02X360766I-18467J-14781D01*
G03X367339Y845355I-29176J23351D01*
G02X391126I11894J-3623D01*
G03X397699Y832891I35749J10887D01*
G37*
G36*
G01Y1285647D02*
G02X360766I-18467J-14781D01*
G03X367339Y1298111I-29176J23351D01*
G02X391126I11894J-3623D01*
G03X397699Y1285647I35749J10887D01*
G37*
G36*
G01X645730Y380135D02*
G02X608797I-18466J-14781D01*
G03X615370Y392599I-29176J23351D01*
G02X639157I11893J-3623D01*
G03X645730Y380135I35749J10887D01*
G37*
G36*
G01Y832891D02*
G02X608797I-18466J-14781D01*
G03X615370Y845355I-29176J23351D01*
G02X639157I11893J-3623D01*
G03X645730Y832891I35749J10887D01*
G37*
G36*
G01Y1285647D02*
G02X608797I-18466J-14781D01*
G03X615370Y1298111I-29176J23351D01*
G02X639157I11893J-3623D01*
G03X645730Y1285647I35749J10887D01*
G37*
G36*
G01X814924Y265984D02*
G02X777991I-18467J-14781D01*
G03X784564Y278448I-29176J23351D01*
G02X808351I11893J-3623D01*
G03X814924Y265984I35749J10887D01*
G37*
G36*
G01Y738425D02*
G02X777991I-18467J-14781D01*
G03X784564Y750889I-29176J23351D01*
G02X808351I11893J-3623D01*
G03X814924Y738425I35749J10887D01*
G37*
G36*
G01X979885Y1090394D02*
G02X942952I-18467J-14781D01*
G03X949525Y1102858I-29176J23351D01*
G02X973312I11894J-3623D01*
G03X979885Y1090394I35749J10887D01*
G37*
G36*
G01Y1432913D02*
G02X942952I-18467J-14781D01*
G03X949525Y1445377I-29176J23351D01*
G02X973312I11894J-3623D01*
G03X979885Y1432913I35749J10887D01*
G37*
G36*
G01X1200357Y558898D02*
G02X1163424I-18467J-14781D01*
G03X1169997Y571362I-29176J23351D01*
G02X1193784I11894J-3623D01*
G03X1200357Y558898I35749J10887D01*
G37*
G36*
G01X1200337Y972261D02*
G02X1163404I-18467J-14781D01*
G03X1169977Y984725I-29176J23351D01*
G02X1193764I11894J-3623D01*
G03X1200337Y972261I35749J10887D01*
G37*
G36*
G01X1200357Y1562835D02*
G02X1163424I-18467J-14781D01*
G03X1169997Y1575299I-29176J23351D01*
G02X1193784I11894J-3623D01*
G03X1200357Y1562835I35749J10887D01*
G37*
G36*
G01X1320337Y380135D02*
G02X1283404I-18467J-14781D01*
G03X1289977Y392599I-29176J23351D01*
G02X1313764I11894J-3623D01*
G03X1320337Y380135I35749J10887D01*
G37*
G36*
G01Y832891D02*
G02X1283404I-18467J-14781D01*
G03X1289977Y845355I-29176J23351D01*
G02X1313764I11894J-3623D01*
G03X1320337Y832891I35749J10887D01*
G37*
G36*
G01Y1285647D02*
G02X1283404I-18467J-14781D01*
G03X1289977Y1298111I-29176J23351D01*
G02X1313764I11894J-3623D01*
G03X1320337Y1285647I35749J10887D01*
G37*
G36*
G01X1568368Y380135D02*
G02X1531435I-18467J-14781D01*
G03X1538008Y392599I-29176J23351D01*
G02X1561795I11894J-3623D01*
G03X1568368Y380135I35749J10887D01*
G37*
G36*
G01Y832891D02*
G02X1531435I-18467J-14781D01*
G03X1538008Y845355I-29176J23351D01*
G02X1561795I11894J-3623D01*
G03X1568368Y832891I35749J10887D01*
G37*
G36*
G01Y1285647D02*
G02X1531435I-18467J-14781D01*
G03X1538008Y1298111I-29176J23351D01*
G02X1561795I11894J-3623D01*
G03X1568368Y1285647I35749J10887D01*
G37*
G36*
G01X1816400Y380135D02*
G02X1779467I-18466J-14781D01*
G03X1786040Y392599I-29176J23351D01*
G02X1809827I11894J-3623D01*
G03X1816400Y380135I35749J10887D01*
G37*
G36*
G01Y832891D02*
G02X1779467I-18466J-14781D01*
G03X1786040Y845355I-29176J23351D01*
G02X1809827I11894J-3623D01*
G03X1816400Y832891I35749J10887D01*
G37*
G36*
G01Y1285647D02*
G02X1779467I-18466J-14781D01*
G03X1786040Y1298111I-29176J23351D01*
G02X1809827I11894J-3623D01*
G03X1816400Y1285647I35749J10887D01*
G37*
%LPC*%
G75*
G54D45*
G01X363248Y-425196D02*
Y-505196D01*
G01D02*
X1639148D01*
G01X359248Y-409196D02*
G02I-12000J0D01*
G01X354098D02*
G02I-6850J0D01*
G01X347248Y-425196D02*
Y-393196D01*
G01X363248Y-425196D02*
X1639148D01*
G01X363248Y-460696D02*
X1639148D01*
G01X363248Y-409196D02*
X331248D01*
G01X720748Y-425196D02*
Y-505196D01*
G01X858248Y-425196D02*
Y-505196D01*
G01X973248Y-425196D02*
Y-505196D01*
G01X1271648Y-425196D02*
Y-505196D01*
G01X1441648Y-425196D02*
Y-505196D01*
G01X1639148Y-425196D02*
Y-505196D01*
G01X1667148Y-409196D02*
G02I-12000J0D01*
G01X1661998D02*
G02I-6850J0D01*
G01X1655148Y-425196D02*
Y-393196D01*
G01X1671148Y-409196D02*
X1639148D01*
G54D46*
G01X394744Y-485863D02*
X395618Y-484988D01*
X396273Y-483530D01*
X396710Y-481487D01*
X396273Y-479738D01*
X395400Y-478571D01*
X393871Y-477696D01*
X387976D01*
Y-495196D01*
X395181D01*
X396710Y-494030D01*
X397583Y-492279D01*
X398020Y-490238D01*
X397583Y-488196D01*
X396273Y-486446D01*
X394744Y-485863D01*
X387976D01*
G01X407441Y-495196D02*
Y-483530D01*
G01Y-485863D02*
X408533Y-484696D01*
X409625Y-483821D01*
X411153Y-483530D01*
X412244Y-483821D01*
X413555Y-484696D01*
G01X423413Y-500446D02*
X424723Y-501029D01*
X426470Y-500446D01*
X427561Y-499280D01*
X428435Y-497821D01*
X429744Y-493155D01*
X432583Y-483530D01*
G01X425596D02*
X429744Y-493155D01*
G01X448991Y-484988D02*
X447463Y-483821D01*
X446153Y-483530D01*
X444406Y-484113D01*
X443096Y-485279D01*
X442223Y-487321D01*
X442004Y-489363D01*
X442223Y-491405D01*
X443096Y-493155D01*
X444406Y-494613D01*
X446153Y-495196D01*
X447681Y-494613D01*
X448991Y-493446D01*
G01X459723Y-487321D02*
X466710D01*
X466055Y-485279D01*
X464963Y-484113D01*
X463435Y-483530D01*
X461906Y-483821D01*
X460596Y-484696D01*
X459723Y-486738D01*
X459286Y-488488D01*
Y-490238D01*
X459723Y-491988D01*
X460815Y-493738D01*
X462125Y-494904D01*
X463653Y-495196D01*
X465181Y-494613D01*
X466710Y-492863D01*
G01X502801Y-479155D02*
X501491Y-478279D01*
X499963Y-477696D01*
X498216D01*
X496251Y-478571D01*
X494723Y-480029D01*
X493631Y-481780D01*
X492758Y-484696D01*
X492539Y-487321D01*
X492976Y-489946D01*
X493631Y-491696D01*
X494941Y-493446D01*
X496470Y-494613D01*
X497998Y-495196D01*
X499526D01*
X501055Y-494613D01*
X502365Y-493738D01*
X503457Y-492572D01*
G01X519428Y-495196D02*
Y-483530D01*
G01Y-485571D02*
X518555Y-484405D01*
X517244Y-483821D01*
X515716Y-483530D01*
X514188Y-484113D01*
X512878Y-485279D01*
X512004Y-487029D01*
X511568Y-489363D01*
X512004Y-491696D01*
X512878Y-493446D01*
X514188Y-494613D01*
X515716Y-495196D01*
X517244Y-494904D01*
X518555Y-494030D01*
X519428Y-492863D01*
G01X529286Y-495196D02*
Y-483530D01*
G01Y-486446D02*
X530160Y-484988D01*
X531470Y-483821D01*
X533216Y-483530D01*
X534744Y-483821D01*
X536055Y-484988D01*
X536710Y-487029D01*
Y-495196D01*
G01X545913Y-500446D02*
X547223Y-501029D01*
X548970Y-500446D01*
X550061Y-499280D01*
X550935Y-497821D01*
X552244Y-493155D01*
X555083Y-483530D01*
G01X548096D02*
X552244Y-493155D01*
G01X567998Y-495196D02*
X566688Y-494904D01*
X565378Y-493738D01*
X564504Y-491696D01*
X564068Y-489363D01*
X564504Y-487029D01*
X565378Y-484988D01*
X566688Y-483821D01*
X567998Y-483530D01*
X569308Y-483821D01*
X570618Y-484988D01*
X571491Y-487029D01*
X571710Y-489363D01*
X571491Y-491696D01*
X570618Y-493738D01*
X569308Y-494904D01*
X567998Y-495196D01*
G01X581786D02*
Y-483530D01*
G01Y-486446D02*
X582660Y-484988D01*
X583970Y-483821D01*
X585716Y-483530D01*
X587244Y-483821D01*
X588555Y-484988D01*
X589210Y-487029D01*
Y-495196D01*
G01X616350D02*
Y-477696D01*
X624646D01*
G01X621590Y-486154D02*
X616350D01*
G01X637998Y-495779D02*
X637561Y-495488D01*
Y-494904D01*
X637998Y-494613D01*
X638435Y-494904D01*
Y-495488D01*
X637998Y-495779D01*
G01X650695Y-495196D02*
Y-477696D01*
X655061D01*
X656808Y-478571D01*
X658118Y-479738D01*
X659210Y-481487D01*
X660083Y-483530D01*
X660301Y-486446D01*
X660083Y-489363D01*
X659210Y-491405D01*
X658118Y-493155D01*
X656808Y-494321D01*
X655061Y-495196D01*
X650695D01*
G01X668631D02*
Y-477696D01*
X673871D01*
X675618Y-478571D01*
X676928Y-480613D01*
X677365Y-482946D01*
X676928Y-485279D01*
X675836Y-487029D01*
X673871Y-487905D01*
X668631D01*
G01X692244Y-485863D02*
X693118Y-484988D01*
X693773Y-483530D01*
X694210Y-481487D01*
X693773Y-479738D01*
X692900Y-478571D01*
X691371Y-477696D01*
X685476D01*
Y-495196D01*
X692681D01*
X694210Y-494030D01*
X695083Y-492279D01*
X695520Y-490238D01*
X695083Y-488196D01*
X693773Y-486446D01*
X692244Y-485863D01*
X685476D01*
G01X501071Y-450196D02*
Y-432696D01*
X506748Y-447279D01*
X512425Y-432696D01*
Y-450196D01*
G01X524248D02*
X522938Y-449904D01*
X521628Y-448738D01*
X520754Y-446696D01*
X520318Y-444363D01*
X520754Y-442029D01*
X521628Y-439988D01*
X522938Y-438821D01*
X524248Y-438530D01*
X525558Y-438821D01*
X526868Y-439988D01*
X527741Y-442029D01*
X527960Y-444363D01*
X527741Y-446696D01*
X526868Y-448738D01*
X525558Y-449904D01*
X524248Y-450196D01*
G01X545678Y-432696D02*
Y-450196D01*
G01Y-447572D02*
X544805Y-449030D01*
X543494Y-449904D01*
X541966Y-450196D01*
X540220Y-449613D01*
X538910Y-448155D01*
X538036Y-446405D01*
X537818Y-444363D01*
X538036Y-442321D01*
X538910Y-440571D01*
X540220Y-439113D01*
X541966Y-438530D01*
X543494Y-438821D01*
X544586Y-439405D01*
X545678Y-440571D01*
G01X555973Y-442321D02*
X562960D01*
X562305Y-440279D01*
X561213Y-439113D01*
X559685Y-438530D01*
X558156Y-438821D01*
X556846Y-439696D01*
X555973Y-441738D01*
X555536Y-443488D01*
Y-445238D01*
X555973Y-446988D01*
X557065Y-448738D01*
X558375Y-449904D01*
X559903Y-450196D01*
X561431Y-449613D01*
X562960Y-447863D01*
G01X576748Y-450196D02*
Y-432696D01*
G01X754448Y-495196D02*
Y-477696D01*
X751828Y-481196D01*
G01Y-495196D02*
X757068D01*
G01X767800Y-487905D02*
X769328Y-485863D01*
X770638Y-484696D01*
X772385Y-484113D01*
X773913Y-484696D01*
X775005Y-485863D01*
X775878Y-487613D01*
X776096Y-489654D01*
X775878Y-491405D01*
X775005Y-493155D01*
X773694Y-494613D01*
X772166Y-495196D01*
X770420Y-494613D01*
X768891Y-492863D01*
X768018Y-490238D01*
X767800Y-487321D01*
X768236Y-483530D01*
X768891Y-481487D01*
X769983Y-479446D01*
X771511Y-477988D01*
X773040Y-477696D01*
X774568Y-478279D01*
X775660Y-479738D01*
G01X784645Y-491696D02*
X785954Y-493738D01*
X787701Y-494904D01*
X789666Y-495196D01*
X791413Y-494904D01*
X793160Y-493446D01*
X794251Y-491696D01*
X794470Y-489946D01*
X794033Y-487905D01*
X792505Y-486446D01*
X790976Y-485863D01*
X789011D01*
G01X790976D02*
X792286Y-484988D01*
X793378Y-483530D01*
X793815Y-481780D01*
X793378Y-480029D01*
X792286Y-478571D01*
X790321Y-477696D01*
X788356Y-477988D01*
X786391Y-479155D01*
G01X806948Y-495196D02*
Y-477696D01*
X804328Y-481196D01*
G01Y-495196D02*
X809568D01*
G01X819645Y-492572D02*
X820954Y-494030D01*
X822483Y-494904D01*
X824448Y-495196D01*
X826413Y-494613D01*
X827941Y-493446D01*
X829033Y-491405D01*
X829251Y-489071D01*
X828815Y-486738D01*
X827723Y-485279D01*
X826194Y-484113D01*
X824666Y-483821D01*
X823138Y-484113D01*
X821173Y-485279D01*
X821828Y-477696D01*
X827723D01*
G01X741331Y-450196D02*
Y-432696D01*
X746571D01*
X748318Y-433571D01*
X749628Y-435613D01*
X750065Y-437946D01*
X749628Y-440279D01*
X748536Y-442029D01*
X746571Y-442905D01*
X741331D01*
G01X768001Y-434155D02*
X766691Y-433279D01*
X765163Y-432696D01*
X763416D01*
X761451Y-433571D01*
X759923Y-435029D01*
X758831Y-436780D01*
X757958Y-439696D01*
X757739Y-442321D01*
X758176Y-444946D01*
X758831Y-446696D01*
X760141Y-448446D01*
X761670Y-449613D01*
X763198Y-450196D01*
X764726D01*
X766255Y-449613D01*
X767565Y-448738D01*
X768657Y-447572D01*
G01X782444Y-440863D02*
X783318Y-439988D01*
X783973Y-438530D01*
X784410Y-436487D01*
X783973Y-434738D01*
X783100Y-433571D01*
X781571Y-432696D01*
X775676D01*
Y-450196D01*
X782881D01*
X784410Y-449030D01*
X785283Y-447279D01*
X785720Y-445238D01*
X785283Y-443196D01*
X783973Y-441446D01*
X782444Y-440863D01*
X775676D01*
G01X791648Y-456029D02*
X804748D01*
G01X810676Y-450196D02*
Y-432696D01*
X820720Y-450196D01*
Y-432696D01*
G01X833198Y-450196D02*
X831451Y-449904D01*
X829923Y-448738D01*
X828613Y-446988D01*
X827739Y-444946D01*
X827303Y-442613D01*
Y-440279D01*
X827739Y-437946D01*
X828613Y-435904D01*
X829923Y-434155D01*
X831451Y-432988D01*
X833198Y-432696D01*
X834944Y-432988D01*
X836473Y-434155D01*
X837783Y-435904D01*
X838657Y-437946D01*
X839093Y-440279D01*
Y-442613D01*
X838657Y-444946D01*
X837783Y-446988D01*
X836473Y-448738D01*
X834944Y-449904D01*
X833198Y-450196D01*
G01X884039Y-432696D02*
X889498Y-450196D01*
X894957Y-432696D01*
G01X911365Y-450196D02*
X902631D01*
Y-432696D01*
X911365D01*
G01X907871Y-441154D02*
X902631D01*
G01X920131Y-450196D02*
Y-432696D01*
X925590D01*
X927336Y-433571D01*
X928428Y-434738D01*
X928865Y-437071D01*
X928428Y-439405D01*
X927118Y-440863D01*
X925590Y-441738D01*
X920131D01*
G01X925590D02*
X928865Y-450196D01*
G01X941998Y-450779D02*
X941561Y-450488D01*
Y-449904D01*
X941998Y-449613D01*
X942435Y-449904D01*
Y-450488D01*
X941998Y-450779D01*
G01X915748Y-495196D02*
Y-477696D01*
X913128Y-481196D01*
G01Y-495196D02*
X918368D01*
G01X1170465Y-477696D02*
Y-495196D01*
X1161731D01*
G01X1148598D02*
Y-477696D01*
X1151218Y-481196D01*
G01Y-495196D02*
X1145978D01*
G01X1131098D02*
Y-477696D01*
X1133718Y-481196D01*
G01Y-495196D02*
X1128478D01*
G01X1112288Y-486446D02*
X1107921D01*
Y-491696D01*
X1109231Y-493446D01*
X1110760Y-494613D01*
X1112943Y-495196D01*
X1115126Y-494613D01*
X1116655Y-493446D01*
X1117965Y-491696D01*
X1118838Y-489654D01*
X1119275Y-487321D01*
Y-485279D01*
X1118838Y-483530D01*
X1117965Y-481487D01*
X1116655Y-479738D01*
X1115345Y-478571D01*
X1113598Y-477696D01*
X1112070D01*
X1110323Y-478279D01*
X1109013Y-479446D01*
G01X1101120Y-495196D02*
Y-477696D01*
X1091076Y-495196D01*
Y-477696D01*
G01X1083401Y-495196D02*
Y-477696D01*
X1079035D01*
X1077288Y-478571D01*
X1075978Y-479738D01*
X1074886Y-481487D01*
X1074013Y-483530D01*
X1073795Y-486446D01*
X1074013Y-489363D01*
X1074886Y-491405D01*
X1075978Y-493155D01*
X1077288Y-494321D01*
X1079035Y-495196D01*
X1083401D01*
G01X1082981Y-432696D02*
Y-450196D01*
X1091715D01*
G01X1108778D02*
Y-438530D01*
G01Y-440571D02*
X1107905Y-439405D01*
X1106594Y-438821D01*
X1105066Y-438530D01*
X1103538Y-439113D01*
X1102228Y-440279D01*
X1101354Y-442029D01*
X1100918Y-444363D01*
X1101354Y-446696D01*
X1102228Y-448446D01*
X1103538Y-449613D01*
X1105066Y-450196D01*
X1106594Y-449904D01*
X1107905Y-449030D01*
X1108778Y-447863D01*
G01X1117763Y-455446D02*
X1119073Y-456029D01*
X1120820Y-455446D01*
X1121911Y-454280D01*
X1122785Y-452821D01*
X1124094Y-448155D01*
X1126933Y-438530D01*
G01X1119946D02*
X1124094Y-448155D01*
G01X1136573Y-442321D02*
X1143560D01*
X1142905Y-440279D01*
X1141813Y-439113D01*
X1140285Y-438530D01*
X1138756Y-438821D01*
X1137446Y-439696D01*
X1136573Y-441738D01*
X1136136Y-443488D01*
Y-445238D01*
X1136573Y-446988D01*
X1137665Y-448738D01*
X1138975Y-449904D01*
X1140503Y-450196D01*
X1142031Y-449613D01*
X1143560Y-447863D01*
G01X1154291Y-450196D02*
Y-438530D01*
G01Y-440863D02*
X1155383Y-439696D01*
X1156475Y-438821D01*
X1158003Y-438530D01*
X1159094Y-438821D01*
X1160405Y-439696D01*
G01X1312898Y-495196D02*
X1311151Y-494904D01*
X1309623Y-493738D01*
X1308313Y-491988D01*
X1307439Y-489946D01*
X1307003Y-487613D01*
Y-485279D01*
X1307439Y-482946D01*
X1308313Y-480904D01*
X1309623Y-479155D01*
X1311151Y-477988D01*
X1312898Y-477696D01*
X1314644Y-477988D01*
X1316173Y-479155D01*
X1317483Y-480904D01*
X1318357Y-482946D01*
X1318793Y-485279D01*
Y-487613D01*
X1318357Y-489946D01*
X1317483Y-491988D01*
X1316173Y-493738D01*
X1314644Y-494904D01*
X1312898Y-495196D01*
G01X1314644Y-490529D02*
X1317265Y-495196D01*
G01X1325595Y-477696D02*
Y-490238D01*
X1326468Y-492863D01*
X1328215Y-494613D01*
X1330398Y-495196D01*
X1332581Y-494613D01*
X1334328Y-492863D01*
X1335201Y-490238D01*
Y-477696D01*
G01X1345278D02*
X1350518D01*
G01X1347898D02*
Y-495196D01*
G01X1345278D02*
X1350518D01*
G01X1360376D02*
Y-477696D01*
X1370420Y-495196D01*
Y-477696D01*
G01X1387701Y-479155D02*
X1386391Y-478279D01*
X1384863Y-477696D01*
X1383116D01*
X1381151Y-478571D01*
X1379623Y-480029D01*
X1378531Y-481780D01*
X1377658Y-484696D01*
X1377439Y-487321D01*
X1377876Y-489946D01*
X1378531Y-491696D01*
X1379841Y-493446D01*
X1381370Y-494613D01*
X1382898Y-495196D01*
X1384426D01*
X1385955Y-494613D01*
X1387265Y-493738D01*
X1388357Y-492572D01*
G01X1400398Y-495196D02*
Y-487321D01*
X1396031Y-477696D01*
G01X1404765D02*
X1400398Y-487321D01*
G01X1290595Y-450196D02*
Y-432696D01*
X1294961D01*
X1296708Y-433571D01*
X1298018Y-434738D01*
X1299110Y-436487D01*
X1299983Y-438530D01*
X1300201Y-441446D01*
X1299983Y-444363D01*
X1299110Y-446405D01*
X1298018Y-448155D01*
X1296708Y-449321D01*
X1294961Y-450196D01*
X1290595D01*
G01X1309623Y-442321D02*
X1316610D01*
X1315955Y-440279D01*
X1314863Y-439113D01*
X1313335Y-438530D01*
X1311806Y-438821D01*
X1310496Y-439696D01*
X1309623Y-441738D01*
X1309186Y-443488D01*
Y-445238D01*
X1309623Y-446988D01*
X1310715Y-448738D01*
X1312025Y-449904D01*
X1313553Y-450196D01*
X1315081Y-449613D01*
X1316610Y-447863D01*
G01X1327123Y-448155D02*
X1328215Y-449321D01*
X1329743Y-450196D01*
X1331053D01*
X1332363Y-449613D01*
X1333236Y-448738D01*
X1333673Y-447572D01*
X1333455Y-445821D01*
X1332581Y-444946D01*
X1328651Y-443196D01*
X1327778Y-441154D01*
X1328215Y-439696D01*
X1329088Y-438821D01*
X1330398Y-438530D01*
X1331708Y-438821D01*
X1333018Y-439696D01*
G01X1347898Y-438530D02*
Y-450196D01*
G01Y-433863D02*
X1347461Y-433571D01*
Y-432988D01*
X1347898Y-432696D01*
X1348335Y-432988D01*
Y-433571D01*
X1347898Y-433863D01*
G01X1362341Y-454571D02*
X1363870Y-455738D01*
X1365616Y-456029D01*
X1367144Y-455738D01*
X1368455Y-454280D01*
X1369328Y-452238D01*
Y-438530D01*
G01Y-440863D02*
X1368455Y-439696D01*
X1367144Y-438821D01*
X1365616Y-438530D01*
X1363870Y-439113D01*
X1362778Y-440279D01*
X1361904Y-442321D01*
X1361468Y-444363D01*
X1361686Y-446113D01*
X1362560Y-448155D01*
X1363870Y-449613D01*
X1365616Y-450196D01*
X1366926Y-449904D01*
X1368455Y-448738D01*
X1369328Y-447572D01*
G01X1379186Y-450196D02*
Y-438530D01*
G01Y-441446D02*
X1380060Y-439988D01*
X1381370Y-438821D01*
X1383116Y-438530D01*
X1384644Y-438821D01*
X1385955Y-439988D01*
X1386610Y-442029D01*
Y-450196D01*
G01X1397123Y-442321D02*
X1404110D01*
X1403455Y-440279D01*
X1402363Y-439113D01*
X1400835Y-438530D01*
X1399306Y-438821D01*
X1397996Y-439696D01*
X1397123Y-441738D01*
X1396686Y-443488D01*
Y-445238D01*
X1397123Y-446988D01*
X1398215Y-448738D01*
X1399525Y-449904D01*
X1401053Y-450196D01*
X1402581Y-449613D01*
X1404110Y-447863D01*
G01X1414841Y-450196D02*
Y-438530D01*
G01Y-440863D02*
X1415933Y-439696D01*
X1417025Y-438821D01*
X1418553Y-438530D01*
X1419644Y-438821D01*
X1420955Y-439696D01*
G01X1461598Y-477696D02*
X1459851Y-478279D01*
X1458541Y-479738D01*
X1457668Y-481487D01*
X1457013Y-483821D01*
X1456795Y-486446D01*
X1457013Y-489071D01*
X1457668Y-491405D01*
X1458541Y-493155D01*
X1459851Y-494613D01*
X1461598Y-495196D01*
X1463344Y-494613D01*
X1464655Y-493155D01*
X1465528Y-491405D01*
X1466183Y-489071D01*
X1466401Y-486446D01*
X1466183Y-483821D01*
X1465528Y-481487D01*
X1464655Y-479738D01*
X1463344Y-478279D01*
X1461598Y-477696D01*
G01X1474950Y-487905D02*
X1476478Y-485863D01*
X1477788Y-484696D01*
X1479535Y-484113D01*
X1481063Y-484696D01*
X1482155Y-485863D01*
X1483028Y-487613D01*
X1483246Y-489654D01*
X1483028Y-491405D01*
X1482155Y-493155D01*
X1480844Y-494613D01*
X1479316Y-495196D01*
X1477570Y-494613D01*
X1476041Y-492863D01*
X1475168Y-490238D01*
X1474950Y-487321D01*
X1475386Y-483530D01*
X1476041Y-481487D01*
X1477133Y-479446D01*
X1478661Y-477988D01*
X1480190Y-477696D01*
X1481718Y-478279D01*
X1482810Y-479738D01*
G01X1492668Y-495779D02*
X1500528Y-477696D01*
G01X1514098D02*
X1512351Y-478279D01*
X1511041Y-479738D01*
X1510168Y-481487D01*
X1509513Y-483821D01*
X1509295Y-486446D01*
X1509513Y-489071D01*
X1510168Y-491405D01*
X1511041Y-493155D01*
X1512351Y-494613D01*
X1514098Y-495196D01*
X1515844Y-494613D01*
X1517155Y-493155D01*
X1518028Y-491405D01*
X1518683Y-489071D01*
X1518901Y-486446D01*
X1518683Y-483821D01*
X1518028Y-481487D01*
X1517155Y-479738D01*
X1515844Y-478279D01*
X1514098Y-477696D01*
G01X1527886Y-493155D02*
X1529415Y-494613D01*
X1531161Y-495196D01*
X1532908Y-494613D01*
X1534436Y-492863D01*
X1535528Y-490238D01*
X1535965Y-487613D01*
Y-484405D01*
X1535528Y-481780D01*
X1534436Y-479446D01*
X1533126Y-478279D01*
X1531598Y-477696D01*
X1529851Y-478279D01*
X1528541Y-479446D01*
X1527668Y-481196D01*
X1527231Y-483530D01*
X1527668Y-485571D01*
X1528760Y-487613D01*
X1530070Y-488780D01*
X1531598Y-489071D01*
X1533344Y-488488D01*
X1534655Y-487029D01*
X1535965Y-484405D01*
G01X1545168Y-495779D02*
X1553028Y-477696D01*
G01X1562450Y-480613D02*
X1563760Y-478863D01*
X1565288Y-477988D01*
X1567035Y-477696D01*
X1569218Y-478279D01*
X1570746Y-479738D01*
X1571183Y-481487D01*
X1570965Y-483238D01*
X1570091Y-484696D01*
X1565725Y-487613D01*
X1563760Y-489654D01*
X1562450Y-492572D01*
X1562013Y-495196D01*
X1571183D01*
G01X1584098Y-477696D02*
X1582351Y-478279D01*
X1581041Y-479738D01*
X1580168Y-481487D01*
X1579513Y-483821D01*
X1579295Y-486446D01*
X1579513Y-489071D01*
X1580168Y-491405D01*
X1581041Y-493155D01*
X1582351Y-494613D01*
X1584098Y-495196D01*
X1585844Y-494613D01*
X1587155Y-493155D01*
X1588028Y-491405D01*
X1588683Y-489071D01*
X1588901Y-486446D01*
X1588683Y-483821D01*
X1588028Y-481487D01*
X1587155Y-479738D01*
X1585844Y-478279D01*
X1584098Y-477696D01*
G01X1601598Y-495196D02*
Y-477696D01*
X1598978Y-481196D01*
G01Y-495196D02*
X1604218D01*
G01X1618661D02*
X1619098Y-491405D01*
X1619753Y-488196D01*
X1620626Y-485279D01*
X1621718Y-482071D01*
X1623465Y-477696D01*
X1614731D01*
G01X1509295Y-450196D02*
Y-432696D01*
X1513661D01*
X1515408Y-433571D01*
X1516718Y-434738D01*
X1517810Y-436487D01*
X1518683Y-438530D01*
X1518901Y-441446D01*
X1518683Y-444363D01*
X1517810Y-446405D01*
X1516718Y-448155D01*
X1515408Y-449321D01*
X1513661Y-450196D01*
X1509295D01*
G01X1535528D02*
Y-438530D01*
G01Y-440571D02*
X1534655Y-439405D01*
X1533344Y-438821D01*
X1531816Y-438530D01*
X1530288Y-439113D01*
X1528978Y-440279D01*
X1528104Y-442029D01*
X1527668Y-444363D01*
X1528104Y-446696D01*
X1528978Y-448446D01*
X1530288Y-449613D01*
X1531816Y-450196D01*
X1533344Y-449904D01*
X1534655Y-449030D01*
X1535528Y-447863D01*
G01X1549098Y-432696D02*
Y-450196D01*
G01X1546041Y-438530D02*
X1552155D01*
G01X1563323Y-442321D02*
X1570310D01*
X1569655Y-440279D01*
X1568563Y-439113D01*
X1567035Y-438530D01*
X1565506Y-438821D01*
X1564196Y-439696D01*
X1563323Y-441738D01*
X1562886Y-443488D01*
Y-445238D01*
X1563323Y-446988D01*
X1564415Y-448738D01*
X1565725Y-449904D01*
X1567253Y-450196D01*
X1568781Y-449613D01*
X1570310Y-447863D01*
M02*
